G04 ================== begin FILE IDENTIFICATION RECORD ==================*
G04 Layout Name:  12433-2a.brd*
G04 Film Name:    TSMD*
G04 File Format:  Gerber RS274X*
G04 File Origin:  Cadence Allegro 16.5-S056*
G04 Origin Date:  Fri Dec 11 16:47:36 2015*
G04 *
G04 Layer:  VIA CLASS/PASTEMASK_TOP*
G04 Layer:  PIN/PASTEMASK_TOP*
G04 Layer:  PACKAGE GEOMETRY/PASTEMASK_TOP*
G04 Layer:  DRAWING FORMAT/LAYER_PCB_STORY*
G04 Layer:  DRAWING FORMAT/LAYER_PAST_T*
G04 Layer:  BOARD GEOMETRY/PANEL_OUTLINE*
G04 *
G04 Offset:    (0.00 0.00)*
G04 Mirror:    No*
G04 Mode:      Positive*
G04 Rotation:  0*
G04 FullContactRelief:  No*
G04 UndefLineWidth:     6.00*
G04 ================== end FILE IDENTIFICATION RECORD ====================*
%FSLAX35Y35*MOIN*%
%IR0*IPPOS*OFA0.00000B0.00000*MIA0B0*SFA1.00000B1.00000*%
%AMMACRO35*
4,1,40,.013,.017,
-.013,.017,
-.013695,.016939,
-.014368,.016759,
-.015,.016464,
-.015571,.016064,
-.016064,.015571,
-.016464,.015,
-.016759,.014368,
-.016939,.013695,
-.017,.013,
-.017,-.013,
-.016939,-.013695,
-.016759,-.014368,
-.016464,-.015,
-.016064,-.015571,
-.015571,-.016064,
-.015,-.016464,
-.014368,-.016759,
-.013695,-.016939,
-.013,-.017,
.013,-.017,
.013695,-.016939,
.014368,-.016759,
.015,-.016464,
.015571,-.016064,
.016064,-.015571,
.016464,-.015,
.016759,-.014368,
.016939,-.013695,
.017,-.013,
.017,.013,
.016939,.013695,
.016759,.014368,
.016464,.015,
.016064,.015571,
.015571,.016064,
.015,.016464,
.014368,.016759,
.013695,.016939,
.013,.017,
0.0*
%
%ADD35MACRO35*%
%AMMACRO26*
4,1,40,.017,-.013,
.017,.013,
.016939,.013695,
.016759,.014368,
.016464,.015,
.016064,.015571,
.015571,.016064,
.015,.016464,
.014368,.016759,
.013695,.016939,
.013,.017,
-.013,.017,
-.013695,.016939,
-.014368,.016759,
-.015,.016464,
-.015571,.016064,
-.016064,.015571,
-.016464,.015,
-.016759,.014368,
-.016939,.013695,
-.017,.013,
-.017,-.013,
-.016939,-.013695,
-.016759,-.014368,
-.016464,-.015,
-.016064,-.015571,
-.015571,-.016064,
-.015,-.016464,
-.014368,-.016759,
-.013695,-.016939,
-.013,-.017,
.013,-.017,
.013695,-.016939,
.014368,-.016759,
.015,-.016464,
.015571,-.016064,
.016064,-.015571,
.016464,-.015,
.016759,-.014368,
.016939,-.013695,
.017,-.013,
0.0*
%
%ADD26MACRO26*%
%ADD28R,.08X.127*%
%ADD42R,.085X.128*%
%ADD46R,.208X.087*%
%ADD34R,.087X.208*%
%ADD11R,.05X.05*%
%AMMACRO69*
4,1,40,-.014,-.008,
-.014,.008,
-.013939,.008695,
-.013759,.009368,
-.013464,.01,
-.013064,.010571,
-.012571,.011064,
-.012,.011464,
-.011368,.011759,
-.010695,.011939,
-.01,.012,
.01,.012,
.010695,.011939,
.011368,.011759,
.012,.011464,
.012571,.011064,
.013064,.010571,
.013464,.01,
.013759,.009368,
.013939,.008695,
.014,.008,
.014,-.008,
.013939,-.008695,
.013759,-.009368,
.013464,-.01,
.013064,-.010571,
.012571,-.011064,
.012,-.011464,
.011368,-.011759,
.010695,-.011939,
.01,-.012,
-.01,-.012,
-.010695,-.011939,
-.011368,-.011759,
-.012,-.011464,
-.012571,-.011064,
-.013064,-.010571,
-.013464,-.01,
-.013759,-.009368,
-.013939,-.008695,
-.014,-.008,
0.0*
%
%ADD69MACRO69*%
%AMMACRO64*
4,1,40,-.007,-.0225,
-.008389,-.022378,
-.009736,-.022018,
-.011,-.021428,
-.012142,-.020628,
-.013128,-.019642,
-.013928,-.0185,
-.014518,-.017236,
-.014878,-.015889,
-.015,-.0145,
-.015,.0145,
-.014878,.015889,
-.014518,.017236,
-.013928,.0185,
-.013128,.019642,
-.012142,.020628,
-.011,.021428,
-.009736,.022018,
-.008389,.022378,
-.007,.0225,
.007,.0225,
.008389,.022378,
.009736,.022018,
.011,.021428,
.012142,.020628,
.013128,.019642,
.013928,.0185,
.014518,.017236,
.014878,.015889,
.015,.0145,
.015,-.0145,
.014878,-.015889,
.014518,-.017236,
.013928,-.0185,
.013128,-.019642,
.012142,-.020628,
.011,-.021428,
.009736,-.022018,
.008389,-.022378,
.007,-.0225,
-.007,-.0225,
0.0*
%
%ADD64MACRO64*%
%AMMACRO36*
4,1,40,.011,-.007,
.011,.007,
.010939,.007695,
.010759,.008368,
.010464,.009,
.010064,.009571,
.009571,.010064,
.009,.010464,
.008368,.010759,
.007695,.010939,
.007,.011,
-.007,.011,
-.007695,.010939,
-.008368,.010759,
-.009,.010464,
-.009571,.010064,
-.010064,.009571,
-.010464,.009,
-.010759,.008368,
-.010939,.007695,
-.011,.007,
-.011,-.007,
-.010939,-.007695,
-.010759,-.008368,
-.010464,-.009,
-.010064,-.009571,
-.009571,-.010064,
-.009,-.010464,
-.008368,-.010759,
-.007695,-.010939,
-.007,-.011,
.007,-.011,
.007695,-.010939,
.008368,-.010759,
.009,-.010464,
.009571,-.010064,
.010064,-.009571,
.010464,-.009,
.010759,-.008368,
.010939,-.007695,
.011,-.007,
0.0*
%
%ADD36MACRO36*%
%AMMACRO14*
4,1,40,.007,.011,
-.007,.011,
-.007695,.010939,
-.008368,.010759,
-.009,.010464,
-.009571,.010064,
-.010064,.009571,
-.010464,.009,
-.010759,.008368,
-.010939,.007695,
-.011,.007,
-.011,-.007,
-.010939,-.007695,
-.010759,-.008368,
-.010464,-.009,
-.010064,-.009571,
-.009571,-.010064,
-.009,-.010464,
-.008368,-.010759,
-.007695,-.010939,
-.007,-.011,
.007,-.011,
.007695,-.010939,
.008368,-.010759,
.009,-.010464,
.009571,-.010064,
.010064,-.009571,
.010464,-.009,
.010759,-.008368,
.010939,-.007695,
.011,-.007,
.011,.007,
.010939,.007695,
.010759,.008368,
.010464,.009,
.010064,.009571,
.009571,.010064,
.009,.010464,
.008368,.010759,
.007695,.010939,
.007,.011,
0.0*
%
%ADD14MACRO14*%
%AMMACRO56*
4,1,40,-.012,.008,
-.012,-.008,
-.011939,-.008695,
-.011759,-.009368,
-.011464,-.01,
-.011064,-.010571,
-.010571,-.011064,
-.01,-.011464,
-.009368,-.011759,
-.008695,-.011939,
-.008,-.012,
.008,-.012,
.008695,-.011939,
.009368,-.011759,
.01,-.011464,
.010571,-.011064,
.011064,-.010571,
.011464,-.01,
.011759,-.009368,
.011939,-.008695,
.012,-.008,
.012,.008,
.011939,.008695,
.011759,.009368,
.011464,.01,
.011064,.010571,
.010571,.011064,
.01,.011464,
.009368,.011759,
.008695,.011939,
.008,.012,
-.008,.012,
-.008695,.011939,
-.009368,.011759,
-.01,.011464,
-.010571,.011064,
-.011064,.010571,
-.011464,.01,
-.011759,.009368,
-.011939,.008695,
-.012,.008,
0.0*
%
%ADD56MACRO56*%
%AMMACRO39*
4,1,40,.008,.012,
-.008,.012,
-.008695,.011939,
-.009368,.011759,
-.01,.011464,
-.010571,.011064,
-.011064,.010571,
-.011464,.01,
-.011759,.009368,
-.011939,.008695,
-.012,.008,
-.012,-.008,
-.011939,-.008695,
-.011759,-.009368,
-.011464,-.01,
-.011064,-.010571,
-.010571,-.011064,
-.01,-.011464,
-.009368,-.011759,
-.008695,-.011939,
-.008,-.012,
.008,-.012,
.008695,-.011939,
.009368,-.011759,
.01,-.011464,
.010571,-.011064,
.011064,-.010571,
.011464,-.01,
.011759,-.009368,
.011939,-.008695,
.012,-.008,
.012,.008,
.011939,.008695,
.011759,.009368,
.011464,.01,
.011064,.010571,
.010571,.011064,
.01,.011464,
.009368,.011759,
.008695,.011939,
.008,.012,
0.0*
%
%ADD39MACRO39*%
%AMMACRO30*
4,1,40,-.013,-.017,
.013,-.017,
.013695,-.016939,
.014368,-.016759,
.015,-.016464,
.015571,-.016064,
.016064,-.015571,
.016464,-.015,
.016759,-.014368,
.016939,-.013695,
.017,-.013,
.017,.013,
.016939,.013695,
.016759,.014368,
.016464,.015,
.016064,.015571,
.015571,.016064,
.015,.016464,
.014368,.016759,
.013695,.016939,
.013,.017,
-.013,.017,
-.013695,.016939,
-.014368,.016759,
-.015,.016464,
-.015571,.016064,
-.016064,.015571,
-.016464,.015,
-.016759,.014368,
-.016939,.013695,
-.017,.013,
-.017,-.013,
-.016939,-.013695,
-.016759,-.014368,
-.016464,-.015,
-.016064,-.015571,
-.015571,-.016064,
-.015,-.016464,
-.014368,-.016759,
-.013695,-.016939,
-.013,-.017,
0.0*
%
%ADD30MACRO30*%
%AMMACRO40*
4,1,40,-.017,.013,
-.017,-.013,
-.016939,-.013695,
-.016759,-.014368,
-.016464,-.015,
-.016064,-.015571,
-.015571,-.016064,
-.015,-.016464,
-.014368,-.016759,
-.013695,-.016939,
-.013,-.017,
.013,-.017,
.013695,-.016939,
.014368,-.016759,
.015,-.016464,
.015571,-.016064,
.016064,-.015571,
.016464,-.015,
.016759,-.014368,
.016939,-.013695,
.017,-.013,
.017,.013,
.016939,.013695,
.016759,.014368,
.016464,.015,
.016064,.015571,
.015571,.016064,
.015,.016464,
.014368,.016759,
.013695,.016939,
.013,.017,
-.013,.017,
-.013695,.016939,
-.014368,.016759,
-.015,.016464,
-.015571,.016064,
-.016064,.015571,
-.016464,.015,
-.016759,.014368,
-.016939,.013695,
-.017,.013,
0.0*
%
%ADD40MACRO40*%
%AMMACRO37*
4,1,40,.011,-.007,
.011,.007,
.010939,.007695,
.010759,.008368,
.010464,.009,
.010064,.009571,
.009571,.010064,
.009,.010464,
.008368,.010759,
.007695,.010939,
.007,.011,
-.007,.011,
-.007695,.010939,
-.008368,.010759,
-.009,.010464,
-.009571,.010064,
-.010064,.009571,
-.010464,.009,
-.010759,.008368,
-.010939,.007695,
-.011,.007,
-.011,-.007,
-.010939,-.007695,
-.010759,-.008368,
-.010464,-.009,
-.010064,-.009571,
-.009571,-.010064,
-.009,-.010464,
-.008368,-.010759,
-.007695,-.010939,
-.007,-.011,
.007,-.011,
.007695,-.010939,
.008368,-.010759,
.009,-.010464,
.009571,-.010064,
.010064,-.009571,
.010464,-.009,
.010759,-.008368,
.010939,-.007695,
.011,-.007,
0.0*
%
%ADD37MACRO37*%
%AMMACRO21*
4,1,40,.007,.011,
-.007,.011,
-.007695,.010939,
-.008368,.010759,
-.009,.010464,
-.009571,.010064,
-.010064,.009571,
-.010464,.009,
-.010759,.008368,
-.010939,.007695,
-.011,.007,
-.011,-.007,
-.010939,-.007695,
-.010759,-.008368,
-.010464,-.009,
-.010064,-.009571,
-.009571,-.010064,
-.009,-.010464,
-.008368,-.010759,
-.007695,-.010939,
-.007,-.011,
.007,-.011,
.007695,-.010939,
.008368,-.010759,
.009,-.010464,
.009571,-.010064,
.010064,-.009571,
.010464,-.009,
.010759,-.008368,
.010939,-.007695,
.011,-.007,
.011,.007,
.010939,.007695,
.010759,.008368,
.010464,.009,
.010064,.009571,
.009571,.010064,
.009,.010464,
.008368,.010759,
.007695,.010939,
.007,.011,
0.0*
%
%ADD21MACRO21*%
%AMMACRO55*
4,1,40,-.012,.008,
-.012,-.008,
-.011939,-.008695,
-.011759,-.009368,
-.011464,-.01,
-.011064,-.010571,
-.010571,-.011064,
-.01,-.011464,
-.009368,-.011759,
-.008695,-.011939,
-.008,-.012,
.008,-.012,
.008695,-.011939,
.009368,-.011759,
.01,-.011464,
.010571,-.011064,
.011064,-.010571,
.011464,-.01,
.011759,-.009368,
.011939,-.008695,
.012,-.008,
.012,.008,
.011939,.008695,
.011759,.009368,
.011464,.01,
.011064,.010571,
.010571,.011064,
.01,.011464,
.009368,.011759,
.008695,.011939,
.008,.012,
-.008,.012,
-.008695,.011939,
-.009368,.011759,
-.01,.011464,
-.010571,.011064,
-.011064,.010571,
-.011464,.01,
-.011759,.009368,
-.011939,.008695,
-.012,.008,
0.0*
%
%ADD55MACRO55*%
%AMMACRO38*
4,1,40,.008,.012,
-.008,.012,
-.008695,.011939,
-.009368,.011759,
-.01,.011464,
-.010571,.011064,
-.011064,.010571,
-.011464,.01,
-.011759,.009368,
-.011939,.008695,
-.012,.008,
-.012,-.008,
-.011939,-.008695,
-.011759,-.009368,
-.011464,-.01,
-.011064,-.010571,
-.010571,-.011064,
-.01,-.011464,
-.009368,-.011759,
-.008695,-.011939,
-.008,-.012,
.008,-.012,
.008695,-.011939,
.009368,-.011759,
.01,-.011464,
.010571,-.011064,
.011064,-.010571,
.011464,-.01,
.011759,-.009368,
.011939,-.008695,
.012,-.008,
.012,.008,
.011939,.008695,
.011759,.009368,
.011464,.01,
.011064,.010571,
.010571,.011064,
.01,.011464,
.009368,.011759,
.008695,.011939,
.008,.012,
0.0*
%
%ADD38MACRO38*%
%AMMACRO31*
4,1,40,-.013,-.017,
.013,-.017,
.013695,-.016939,
.014368,-.016759,
.015,-.016464,
.015571,-.016064,
.016064,-.015571,
.016464,-.015,
.016759,-.014368,
.016939,-.013695,
.017,-.013,
.017,.013,
.016939,.013695,
.016759,.014368,
.016464,.015,
.016064,.015571,
.015571,.016064,
.015,.016464,
.014368,.016759,
.013695,.016939,
.013,.017,
-.013,.017,
-.013695,.016939,
-.014368,.016759,
-.015,.016464,
-.015571,.016064,
-.016064,.015571,
-.016464,.015,
-.016759,.014368,
-.016939,.013695,
-.017,.013,
-.017,-.013,
-.016939,-.013695,
-.016759,-.014368,
-.016464,-.015,
-.016064,-.015571,
-.015571,-.016064,
-.015,-.016464,
-.014368,-.016759,
-.013695,-.016939,
-.013,-.017,
0.0*
%
%ADD31MACRO31*%
%AMMACRO41*
4,1,40,-.017,.013,
-.017,-.013,
-.016939,-.013695,
-.016759,-.014368,
-.016464,-.015,
-.016064,-.015571,
-.015571,-.016064,
-.015,-.016464,
-.014368,-.016759,
-.013695,-.016939,
-.013,-.017,
.013,-.017,
.013695,-.016939,
.014368,-.016759,
.015,-.016464,
.015571,-.016064,
.016064,-.015571,
.016464,-.015,
.016759,-.014368,
.016939,-.013695,
.017,-.013,
.017,.013,
.016939,.013695,
.016759,.014368,
.016464,.015,
.016064,.015571,
.015571,.016064,
.015,.016464,
.014368,.016759,
.013695,.016939,
.013,.017,
-.013,.017,
-.013695,.016939,
-.014368,.016759,
-.015,.016464,
-.015571,.016064,
-.016064,.015571,
-.016464,.015,
-.016759,.014368,
-.016939,.013695,
-.017,.013,
0.0*
%
%ADD41MACRO41*%
%ADD44R,.135X.101*%
%ADD72R,.022X.04*%
%ADD50R,.04X.023*%
%ADD58R,.06X.012*%
%ADD45R,.012X.06*%
%ADD63R,.04X.016*%
%ADD62R,.014X.06*%
%ADD27R,.045X.03*%
%ADD18R,.03X.045*%
%ADD70R,.03X.046*%
%ADD43R,.03X.064*%
%ADD10C,.14*%
%ADD66R,.045X.016*%
%ADD65R,.016X.045*%
%ADD61R,.08X.071*%
%ADD12R,.05X.065*%
%ADD48R,.065X.05*%
%ADD68R,.071X.063*%
%ADD60R,.065X.025*%
%ADD29R,.055X.035*%
%ADD54R,.09X.045*%
%ADD52R,.045X.055*%
%ADD51R,.035X.055*%
%ADD24R,.048X.016*%
%ADD59R,.055X.045*%
%ADD47R,.016X.048*%
%ADD67R,.122X.122*%
%ADD20R,.09X.095*%
%AMMACRO71*
4,1,40,.007,.0225,
.008389,.022378,
.009736,.022018,
.011,.021428,
.012142,.020628,
.013128,.019642,
.013928,.0185,
.014518,.017236,
.014878,.015889,
.015,.0145,
.015,-.0145,
.014878,-.015889,
.014518,-.017236,
.013928,-.0185,
.013128,-.019642,
.012142,-.020628,
.011,-.021428,
.009736,-.022018,
.008389,-.022378,
.007,-.0225,
-.007,-.0225,
-.008389,-.022378,
-.009736,-.022018,
-.011,-.021428,
-.012142,-.020628,
-.013128,-.019642,
-.013928,-.0185,
-.014518,-.017236,
-.014878,-.015889,
-.015,-.0145,
-.015,.0145,
-.014878,.015889,
-.014518,.017236,
-.013928,.0185,
-.013128,.019642,
-.012142,.020628,
-.011,.021428,
-.009736,.022018,
-.008389,.022378,
-.007,.0225,
.007,.0225,
0.0*
%
%ADD71MACRO71*%
%ADD53R,.095X.09*%
%ADD49R,.059X.089*%
%AMMACRO33*
4,1,40,.012,-.008,
.012,.008,
.011939,.008695,
.011759,.009368,
.011464,.01,
.011064,.010571,
.010571,.011064,
.01,.011464,
.009368,.011759,
.008695,.011939,
.008,.012,
-.008,.012,
-.008695,.011939,
-.009368,.011759,
-.01,.011464,
-.010571,.011064,
-.011064,.010571,
-.011464,.01,
-.011759,.009368,
-.011939,.008695,
-.012,.008,
-.012,-.008,
-.011939,-.008695,
-.011759,-.009368,
-.011464,-.01,
-.011064,-.010571,
-.010571,-.011064,
-.01,-.011464,
-.009368,-.011759,
-.008695,-.011939,
-.008,-.012,
.008,-.012,
.008695,-.011939,
.009368,-.011759,
.01,-.011464,
.010571,-.011064,
.011064,-.010571,
.011464,-.01,
.011759,-.009368,
.011939,-.008695,
.012,-.008,
0.0*
%
%ADD33MACRO33*%
%AMMACRO23*
4,1,40,-.008,-.012,
.008,-.012,
.008695,-.011939,
.009368,-.011759,
.01,-.011464,
.010571,-.011064,
.011064,-.010571,
.011464,-.01,
.011759,-.009368,
.011939,-.008695,
.012,-.008,
.012,.008,
.011939,.008695,
.011759,.009368,
.011464,.01,
.011064,.010571,
.010571,.011064,
.01,.011464,
.009368,.011759,
.008695,.011939,
.008,.012,
-.008,.012,
-.008695,.011939,
-.009368,.011759,
-.01,.011464,
-.010571,.011064,
-.011064,.010571,
-.011464,.01,
-.011759,.009368,
-.011939,.008695,
-.012,.008,
-.012,-.008,
-.011939,-.008695,
-.011759,-.009368,
-.011464,-.01,
-.011064,-.010571,
-.010571,-.011064,
-.01,-.011464,
-.009368,-.011759,
-.008695,-.011939,
-.008,-.012,
0.0*
%
%ADD23MACRO23*%
%AMMACRO19*
4,1,40,-.007,-.011,
.007,-.011,
.007695,-.010939,
.008368,-.010759,
.009,-.010464,
.009571,-.010064,
.010064,-.009571,
.010464,-.009,
.010759,-.008368,
.010939,-.007695,
.011,-.007,
.011,.007,
.010939,.007695,
.010759,.008368,
.010464,.009,
.010064,.009571,
.009571,.010064,
.009,.010464,
.008368,.010759,
.007695,.010939,
.007,.011,
-.007,.011,
-.007695,.010939,
-.008368,.010759,
-.009,.010464,
-.009571,.010064,
-.010064,.009571,
-.010464,.009,
-.010759,.008368,
-.010939,.007695,
-.011,.007,
-.011,-.007,
-.010939,-.007695,
-.010759,-.008368,
-.010464,-.009,
-.010064,-.009571,
-.009571,-.010064,
-.009,-.010464,
-.008368,-.010759,
-.007695,-.010939,
-.007,-.011,
0.0*
%
%ADD19MACRO19*%
%AMMACRO15*
4,1,40,-.011,.007,
-.011,-.007,
-.010939,-.007695,
-.010759,-.008368,
-.010464,-.009,
-.010064,-.009571,
-.009571,-.010064,
-.009,-.010464,
-.008368,-.010759,
-.007695,-.010939,
-.007,-.011,
.007,-.011,
.007695,-.010939,
.008368,-.010759,
.009,-.010464,
.009571,-.010064,
.010064,-.009571,
.010464,-.009,
.010759,-.008368,
.010939,-.007695,
.011,-.007,
.011,.007,
.010939,.007695,
.010759,.008368,
.010464,.009,
.010064,.009571,
.009571,.010064,
.009,.010464,
.008368,.010759,
.007695,.010939,
.007,.011,
-.007,.011,
-.007695,.010939,
-.008368,.010759,
-.009,.010464,
-.009571,.010064,
-.010064,.009571,
-.010464,.009,
-.010759,.008368,
-.010939,.007695,
-.011,.007,
0.0*
%
%ADD15MACRO15*%
%AMMACRO25*
4,1,40,.017,-.013,
.017,.013,
.016939,.013695,
.016759,.014368,
.016464,.015,
.016064,.015571,
.015571,.016064,
.015,.016464,
.014368,.016759,
.013695,.016939,
.013,.017,
-.013,.017,
-.013695,.016939,
-.014368,.016759,
-.015,.016464,
-.015571,.016064,
-.016064,.015571,
-.016464,.015,
-.016759,.014368,
-.016939,.013695,
-.017,.013,
-.017,-.013,
-.016939,-.013695,
-.016759,-.014368,
-.016464,-.015,
-.016064,-.015571,
-.015571,-.016064,
-.015,-.016464,
-.014368,-.016759,
-.013695,-.016939,
-.013,-.017,
.013,-.017,
.013695,-.016939,
.014368,-.016759,
.015,-.016464,
.015571,-.016064,
.016064,-.015571,
.016464,-.015,
.016759,-.014368,
.016939,-.013695,
.017,-.013,
0.0*
%
%ADD25MACRO25*%
%AMMACRO13*
4,1,40,.013,.017,
-.013,.017,
-.013695,.016939,
-.014368,.016759,
-.015,.016464,
-.015571,.016064,
-.016064,.015571,
-.016464,.015,
-.016759,.014368,
-.016939,.013695,
-.017,.013,
-.017,-.013,
-.016939,-.013695,
-.016759,-.014368,
-.016464,-.015,
-.016064,-.015571,
-.015571,-.016064,
-.015,-.016464,
-.014368,-.016759,
-.013695,-.016939,
-.013,-.017,
.013,-.017,
.013695,-.016939,
.014368,-.016759,
.015,-.016464,
.015571,-.016064,
.016064,-.015571,
.016464,-.015,
.016759,-.014368,
.016939,-.013695,
.017,-.013,
.017,.013,
.016939,.013695,
.016759,.014368,
.016464,.015,
.016064,.015571,
.015571,.016064,
.015,.016464,
.014368,.016759,
.013695,.016939,
.013,.017,
0.0*
%
%ADD13MACRO13*%
%AMMACRO32*
4,1,40,.012,-.008,
.012,.008,
.011939,.008695,
.011759,.009368,
.011464,.01,
.011064,.010571,
.010571,.011064,
.01,.011464,
.009368,.011759,
.008695,.011939,
.008,.012,
-.008,.012,
-.008695,.011939,
-.009368,.011759,
-.01,.011464,
-.010571,.011064,
-.011064,.010571,
-.011464,.01,
-.011759,.009368,
-.011939,.008695,
-.012,.008,
-.012,-.008,
-.011939,-.008695,
-.011759,-.009368,
-.011464,-.01,
-.011064,-.010571,
-.010571,-.011064,
-.01,-.011464,
-.009368,-.011759,
-.008695,-.011939,
-.008,-.012,
.008,-.012,
.008695,-.011939,
.009368,-.011759,
.01,-.011464,
.010571,-.011064,
.011064,-.010571,
.011464,-.01,
.011759,-.009368,
.011939,-.008695,
.012,-.008,
0.0*
%
%ADD32MACRO32*%
%AMMACRO22*
4,1,40,-.008,-.012,
.008,-.012,
.008695,-.011939,
.009368,-.011759,
.01,-.011464,
.010571,-.011064,
.011064,-.010571,
.011464,-.01,
.011759,-.009368,
.011939,-.008695,
.012,-.008,
.012,.008,
.011939,.008695,
.011759,.009368,
.011464,.01,
.011064,.010571,
.010571,.011064,
.01,.011464,
.009368,.011759,
.008695,.011939,
.008,.012,
-.008,.012,
-.008695,.011939,
-.009368,.011759,
-.01,.011464,
-.010571,.011064,
-.011064,.010571,
-.011464,.01,
-.011759,.009368,
-.011939,.008695,
-.012,.008,
-.012,-.008,
-.011939,-.008695,
-.011759,-.009368,
-.011464,-.01,
-.011064,-.010571,
-.010571,-.011064,
-.01,-.011464,
-.009368,-.011759,
-.008695,-.011939,
-.008,-.012,
0.0*
%
%ADD22MACRO22*%
%AMMACRO17*
4,1,40,-.007,-.011,
.007,-.011,
.007695,-.010939,
.008368,-.010759,
.009,-.010464,
.009571,-.010064,
.010064,-.009571,
.010464,-.009,
.010759,-.008368,
.010939,-.007695,
.011,-.007,
.011,.007,
.010939,.007695,
.010759,.008368,
.010464,.009,
.010064,.009571,
.009571,.010064,
.009,.010464,
.008368,.010759,
.007695,.010939,
.007,.011,
-.007,.011,
-.007695,.010939,
-.008368,.010759,
-.009,.010464,
-.009571,.010064,
-.010064,.009571,
-.010464,.009,
-.010759,.008368,
-.010939,.007695,
-.011,.007,
-.011,-.007,
-.010939,-.007695,
-.010759,-.008368,
-.010464,-.009,
-.010064,-.009571,
-.009571,-.010064,
-.009,-.010464,
-.008368,-.010759,
-.007695,-.010939,
-.007,-.011,
0.0*
%
%ADD17MACRO17*%
%AMMACRO16*
4,1,40,-.011,.007,
-.011,-.007,
-.010939,-.007695,
-.010759,-.008368,
-.010464,-.009,
-.010064,-.009571,
-.009571,-.010064,
-.009,-.010464,
-.008368,-.010759,
-.007695,-.010939,
-.007,-.011,
.007,-.011,
.007695,-.010939,
.008368,-.010759,
.009,-.010464,
.009571,-.010064,
.010064,-.009571,
.010464,-.009,
.010759,-.008368,
.010939,-.007695,
.011,-.007,
.011,.007,
.010939,.007695,
.010759,.008368,
.010464,.009,
.010064,.009571,
.009571,.010064,
.009,.010464,
.008368,.010759,
.007695,.010939,
.007,.011,
-.007,.011,
-.007695,.010939,
-.008368,.010759,
-.009,.010464,
-.009571,.010064,
-.010064,.009571,
-.010464,.009,
-.010759,.008368,
-.010939,.007695,
-.011,.007,
0.0*
%
%ADD16MACRO16*%
%ADD73C,.02*%
%ADD74C,.006*%
G75*
%LPD*%
G75*
G36*
G01X77800Y444315D02*
X86350D01*
Y453265D01*
X77800D01*
Y444315D01*
G37*
G36*
G01X66650D02*
X75200D01*
Y453265D01*
X66650D01*
Y444315D01*
G37*
G36*
G01X77800Y455865D02*
X86350D01*
Y464815D01*
X77800D01*
Y455865D01*
G37*
G36*
G01X66650D02*
X75200D01*
Y464815D01*
X66650D01*
Y455865D01*
G37*
G36*
G01X69200Y1579915D02*
X77750D01*
Y1588865D01*
X69200D01*
Y1579915D01*
G37*
G36*
G01X58050D02*
X66600D01*
Y1588865D01*
X58050D01*
Y1579915D01*
G37*
G36*
G01X69200Y1591465D02*
X77750D01*
Y1600415D01*
X69200D01*
Y1591465D01*
G37*
G36*
G01X58050D02*
X66600D01*
Y1600415D01*
X58050D01*
Y1591465D01*
G37*
G36*
G01X105300Y443815D02*
X113850D01*
Y452765D01*
X105300D01*
Y443815D01*
G37*
G36*
G01X94150D02*
X102700D01*
Y452765D01*
X94150D01*
Y443815D01*
G37*
G36*
G01X105300Y455365D02*
X113850D01*
Y464315D01*
X105300D01*
Y455365D01*
G37*
G36*
G01X94150D02*
X102700D01*
Y464315D01*
X94150D01*
Y455365D01*
G37*
G36*
G01X108556Y686015D02*
Y692015D01*
X104356D01*
Y686015D01*
X108556D01*
G37*
G36*
G01Y677815D02*
Y683815D01*
X104356D01*
Y677815D01*
X108556D01*
G37*
G36*
G01X102156Y686015D02*
Y692015D01*
X97956D01*
Y686015D01*
X102156D01*
G37*
G36*
G01Y677815D02*
Y683815D01*
X97956D01*
Y677815D01*
X102156D01*
G37*
G36*
G01X126150Y1579815D02*
X134700D01*
Y1588765D01*
X126150D01*
Y1579815D01*
G37*
G36*
G01Y1591365D02*
X134700D01*
Y1600315D01*
X126150D01*
Y1591365D01*
G37*
G36*
G01X102300Y1579815D02*
X110850D01*
Y1588765D01*
X102300D01*
Y1579815D01*
G37*
G36*
G01X91150D02*
X99700D01*
Y1588765D01*
X91150D01*
Y1579815D01*
G37*
G36*
G01X102300Y1591365D02*
X110850D01*
Y1600315D01*
X102300D01*
Y1591365D01*
G37*
G36*
G01X91150D02*
X99700D01*
Y1600315D01*
X91150D01*
Y1591365D01*
G37*
G36*
G01X149800Y443815D02*
X158350D01*
Y452765D01*
X149800D01*
Y443815D01*
G37*
G36*
G01X138650D02*
X147200D01*
Y452765D01*
X138650D01*
Y443815D01*
G37*
G36*
G01X177800D02*
X186350D01*
Y452765D01*
X177800D01*
Y443815D01*
G37*
G36*
G01X166650D02*
X175200D01*
Y452765D01*
X166650D01*
Y443815D01*
G37*
G36*
G01X149800Y455365D02*
X158350D01*
Y464315D01*
X149800D01*
Y455365D01*
G37*
G36*
G01X138650D02*
X147200D01*
Y464315D01*
X138650D01*
Y455365D01*
G37*
G36*
G01X177800D02*
X186350D01*
Y464315D01*
X177800D01*
Y455365D01*
G37*
G36*
G01X166650D02*
X175200D01*
Y464315D01*
X166650D01*
Y455365D01*
G37*
G36*
G01X171300Y1579815D02*
X179850D01*
Y1588765D01*
X171300D01*
Y1579815D01*
G37*
G36*
G01X160150D02*
X168700D01*
Y1588765D01*
X160150D01*
Y1579815D01*
G37*
G36*
G01X171300Y1591365D02*
X179850D01*
Y1600315D01*
X171300D01*
Y1591365D01*
G37*
G36*
G01X160150D02*
X168700D01*
Y1600315D01*
X160150D01*
Y1591365D01*
G37*
G36*
G01X137300Y1579815D02*
X145850D01*
Y1588765D01*
X137300D01*
Y1579815D01*
G37*
G36*
G01Y1591365D02*
X145850D01*
Y1600315D01*
X137300D01*
Y1591365D01*
G37*
G54D10*
X-222440Y19685D03*
Y1948818D03*
X643700Y19685D03*
Y1948818D03*
G54D20*
X22900Y397800D03*
Y418300D03*
X19100Y667000D03*
X36600Y1551500D03*
X81100Y398500D03*
X47700Y397800D03*
X81100Y419000D03*
X47700Y418300D03*
X43900Y667000D03*
X73600Y798400D03*
X63700Y1090600D03*
X88500D03*
X61400Y1551500D03*
X137900Y88500D03*
X113100D03*
X105900Y398500D03*
Y419000D03*
X98400Y798400D03*
X185300Y397900D03*
X160500D03*
X185200Y356700D03*
X160400D03*
X185400Y376900D03*
X160600D03*
X185300Y418400D03*
X160500D03*
X184900Y1531500D03*
X160100D03*
X185000Y1551600D03*
X160200D03*
G54D11*
X-181139Y20007D03*
X-180444Y1947256D03*
X150000Y64500D03*
X152500Y1906000D03*
X601704Y21248D03*
X602399Y1948497D03*
G54D12*
X27900Y246900D03*
X25300Y328500D03*
X36300D03*
X16200Y1657100D03*
X27200D03*
X15800Y1699200D03*
X26800D03*
X38900Y246900D03*
X124696Y1392300D03*
X135696D03*
X106000Y1387500D03*
X117000D03*
X154000D03*
X143000D03*
G54D21*
X33400Y570800D03*
X27700Y1106000D03*
X22000Y1640200D03*
X34100Y1774400D03*
X23300Y1769600D03*
X70700Y63500D03*
X60300Y171300D03*
Y183300D03*
Y167300D03*
Y187300D03*
X61200Y221000D03*
X49900Y217400D03*
X36082Y264217D03*
X60300Y280000D03*
X81944Y694635D03*
X83400Y682200D03*
X68700Y730000D03*
X72100Y1004300D03*
X63000Y1020600D03*
X75700Y1025400D03*
X75800Y1020900D03*
X41400Y1096000D03*
X72200Y1175100D03*
X38400Y1788200D03*
X102100Y549600D03*
X87100Y569900D03*
X94700Y671000D03*
X119000Y660200D03*
X108300Y662200D03*
X91200Y707900D03*
X89700Y733400D03*
X113100Y1421600D03*
X107500Y1408100D03*
X133200Y1428300D03*
X94700Y1446500D03*
X153500Y430800D03*
X148700Y568000D03*
X156200Y587000D03*
X166100Y626700D03*
X177700Y624300D03*
X151404Y1394000D03*
X143900Y1466400D03*
Y1462400D03*
X143600Y1453300D03*
X160700Y1458000D03*
G54D30*
X33600Y1769900D03*
X81300Y71500D03*
X63800Y662300D03*
Y657600D03*
X54300Y1764700D03*
X115800Y769100D03*
Y764100D03*
X105300Y1058400D03*
Y1053700D03*
X187900Y1652700D03*
Y1648000D03*
X147447Y1878698D03*
X147400Y1883700D03*
G54D22*
X35000Y581300D03*
X58100Y1030800D03*
X87400Y574100D03*
X149500Y578600D03*
X164600Y608500D03*
X150500Y699200D03*
G54D13*
X34400Y294300D03*
X78247Y61398D03*
X50600Y252800D03*
X85929Y533679D03*
X67900Y591000D03*
X71000Y986600D03*
X62000Y1025000D03*
X111300Y380100D03*
X101500Y986000D03*
Y990800D03*
X89200Y1455500D03*
X101200Y1474500D03*
X160300Y532100D03*
X160100Y553300D03*
X176421Y613535D03*
X154700Y1462500D03*
G54D31*
X28000Y1769900D03*
X75700Y71500D03*
X58200Y662300D03*
Y657600D03*
X48700Y1764700D03*
X110200Y769100D03*
Y764100D03*
X99700Y1058400D03*
Y1053700D03*
X182300Y1652700D03*
Y1648000D03*
X141847Y1878698D03*
X141800Y1883700D03*
G54D40*
X47498Y238899D03*
X52200Y238900D03*
X62700Y254200D03*
X45100Y577300D03*
X81500Y727600D03*
X63202Y1128347D03*
X103900Y476600D03*
X96300Y557700D03*
X129065Y673094D03*
X123465D03*
X124900Y722600D03*
X94500Y976700D03*
X130800Y975800D03*
X133500Y1471200D03*
X146700Y476700D03*
X163300Y696500D03*
X144300Y1111300D03*
X149002Y1111347D03*
G54D32*
X30300Y1787800D03*
X64500Y573000D03*
X81900Y966200D03*
X71200Y1144500D03*
X87000Y1143000D03*
X94800Y1431500D03*
Y1434900D03*
X133300Y1432000D03*
X94800Y1442800D03*
X163400Y549300D03*
X144300Y695500D03*
G54D23*
X35000Y584900D03*
X58100Y1034400D03*
X87400Y577700D03*
X149500Y582200D03*
X164600Y612100D03*
X150500Y702800D03*
G54D50*
X77400Y980050D03*
Y976300D03*
Y972550D03*
X88000D03*
Y976300D03*
Y980050D03*
G54D41*
X47498Y244499D03*
X52200Y244500D03*
X62700Y259800D03*
X45100Y582900D03*
X81500Y733200D03*
X63202Y1133947D03*
X103900Y482200D03*
X96300Y563300D03*
X129065Y678694D03*
X123465D03*
X124900Y728200D03*
X94500Y982300D03*
X130800Y981400D03*
X133500Y1476800D03*
X146700Y482300D03*
X163300Y702100D03*
X144300Y1116900D03*
X149002Y1116947D03*
G54D14*
X32682Y264217D03*
X30000Y570800D03*
X24300Y1106000D03*
X18600Y1640200D03*
X30700Y1774400D03*
X19900Y1769600D03*
X35000Y1788200D03*
X67300Y63500D03*
X56900Y171300D03*
Y183300D03*
Y167300D03*
Y187300D03*
X57800Y221000D03*
X46500Y217400D03*
X56900Y280000D03*
X83700Y569900D03*
X78544Y694635D03*
X80000Y682200D03*
X86300Y733400D03*
X65300Y730000D03*
X68700Y1004300D03*
X59600Y1020600D03*
X72300Y1025400D03*
X72400Y1020900D03*
X38000Y1096000D03*
X68800Y1175100D03*
X98700Y549600D03*
X91300Y671000D03*
X115600Y660200D03*
X104900Y662200D03*
X87800Y707900D03*
X109700Y1421600D03*
X104100Y1408100D03*
X129800Y1428300D03*
X91300Y1446500D03*
X150100Y430800D03*
X145300Y568000D03*
X152800Y587000D03*
X162700Y626700D03*
X174300Y624300D03*
X148004Y1394000D03*
X140500Y1466400D03*
Y1462400D03*
X140200Y1453300D03*
X157300Y1458000D03*
G54D15*
X32700Y253500D03*
X19283Y307282D03*
X32900Y1660800D03*
X25900Y1721700D03*
X56600Y191600D03*
X57400Y207900D03*
X56900Y236600D03*
X63000Y264300D03*
X39200Y343800D03*
X81400Y530500D03*
X78400Y587600D03*
X49600Y573500D03*
X61400Y673400D03*
X57400D03*
X64100Y909400D03*
X77002Y1134497D03*
X83500Y1461800D03*
X96100Y530500D03*
X124900Y585204D03*
X120800D03*
X93065Y594071D03*
X97265D03*
X92465Y606971D03*
X95200Y662300D03*
X110900Y881400D03*
X102600D03*
X119300D03*
X122529Y952344D03*
X117529D03*
X112529D03*
X100500Y1420300D03*
X91500D03*
X105000D03*
X135000Y1408404D03*
X134700Y1400604D03*
X107500Y1486800D03*
X170600Y529100D03*
X155600Y529000D03*
X158000Y575200D03*
X170200Y623700D03*
X180365Y642371D03*
X137765Y658671D03*
X154500Y683800D03*
X149500Y708300D03*
X147900Y999700D03*
X152100Y999800D03*
X163500Y994300D03*
X159500D03*
X143800Y999800D03*
X137500Y1440300D03*
G54D33*
X26700Y1787800D03*
X60900Y573000D03*
X78300Y966200D03*
X83400Y1143000D03*
X67600Y1144500D03*
X91200Y1431500D03*
Y1434900D03*
X129700Y1432000D03*
X91200Y1442800D03*
X159800Y549300D03*
X140700Y695500D03*
G54D24*
X36250Y690560D03*
Y688000D03*
Y685440D03*
X51750Y690560D03*
Y688000D03*
Y685440D03*
X58250D03*
Y690560D03*
X42750Y685440D03*
Y690560D03*
G54D51*
X70202Y1138347D03*
Y1125047D03*
X41600Y1767550D03*
Y1754250D03*
X88502Y1136247D03*
Y1122947D03*
G54D60*
X93206Y677415D03*
Y682415D03*
Y687415D03*
Y692415D03*
X113306D03*
Y687415D03*
Y682415D03*
Y677415D03*
G54D42*
X69635Y361900D03*
X110735Y361800D03*
X140465D03*
X99365Y361900D03*
X187565Y1507700D03*
X157835D03*
G54D16*
X32700Y256900D03*
X19283Y310682D03*
X32900Y1664200D03*
X25900Y1725100D03*
X56600Y195000D03*
X57400Y211300D03*
X56900Y240000D03*
X63000Y267700D03*
X39200Y347200D03*
X81400Y533900D03*
X78400Y591000D03*
X49600Y576900D03*
X61400Y676800D03*
X57400D03*
X64100Y912800D03*
X77002Y1137897D03*
X83500Y1465200D03*
X96100Y533900D03*
X124900Y588604D03*
X120800D03*
X93065Y597471D03*
X97265D03*
X92465Y610371D03*
X95200Y665700D03*
X110900Y884800D03*
X102600D03*
X119300D03*
X122529Y955744D03*
X117529D03*
X112529D03*
X135000Y1411804D03*
X134700Y1404004D03*
X100500Y1423700D03*
X91500D03*
X105000D03*
X107500Y1490200D03*
X170600Y532500D03*
X155600Y532400D03*
X158000Y578600D03*
X170200Y627100D03*
X180365Y645771D03*
X137765Y662071D03*
X154500Y687200D03*
X149500Y711700D03*
X147900Y1003100D03*
X152100Y1003200D03*
X163500Y997700D03*
X159500D03*
X143800Y1003200D03*
X137500Y1443700D03*
G54D25*
X24100Y690900D03*
X28900D03*
X74100Y576200D03*
X65635Y693906D03*
X70535D03*
X82000Y708200D03*
X72200Y711000D03*
X67200D03*
X70800Y981400D03*
X64200Y1004100D03*
X81398Y1137753D03*
X92300Y878454D03*
X87500D03*
X94000Y962800D03*
X103500Y979800D03*
X129900Y992500D03*
X140400Y572400D03*
X158535Y609679D03*
G54D52*
X80200Y1477500D03*
X107600Y558300D03*
X115200D03*
X87800Y1477500D03*
X106770Y1480640D03*
X99170D03*
X183700Y1606500D03*
X180700Y1641000D03*
X188300D03*
X191300Y1606500D03*
G54D61*
X134709Y710500D03*
X117291D03*
G54D43*
X69000Y440000D03*
X74000D03*
X79000D03*
X84000D03*
X60400Y1575600D03*
X65400D03*
X70400D03*
X75400D03*
X96500Y439500D03*
X101500D03*
X106500D03*
X111500D03*
X128500Y1575500D03*
X133500D03*
X93500D03*
X98500D03*
X103500D03*
X108500D03*
X141000Y439500D03*
X146000D03*
X151000D03*
X156000D03*
X169000D03*
X174000D03*
X179000D03*
X184000D03*
X162500Y1575500D03*
X167500D03*
X172500D03*
X177500D03*
X138500D03*
X143500D03*
G54D70*
X141100Y1401696D03*
Y1410096D03*
X158600Y1446404D03*
Y1438004D03*
G54D34*
X72200Y86200D03*
X72602Y757897D03*
X63700Y1050100D03*
X99000Y86200D03*
X99402Y757897D03*
X90500Y1050100D03*
G54D17*
X32800Y272300D03*
X29100Y321300D03*
X30100Y1083600D03*
X18600Y1644300D03*
X18400Y1720700D03*
X20200Y1692800D03*
X85800Y71500D03*
X56900Y155300D03*
Y163300D03*
Y179300D03*
Y159300D03*
Y175300D03*
X46500Y213400D03*
X57800Y217000D03*
X56900Y199300D03*
X70800Y431300D03*
X61000Y577200D03*
X78556Y690465D03*
X80700Y686400D03*
X83996Y848500D03*
Y844100D03*
Y852900D03*
X84000Y857200D03*
Y865700D03*
Y861500D03*
X45400Y916400D03*
X68700Y999800D03*
X84300Y1484000D03*
X49400Y1769800D03*
X88303Y61502D03*
X117900Y437500D03*
X125956Y692165D03*
X125856Y688065D03*
Y683665D03*
X112900Y670600D03*
X111900Y1408200D03*
X91300Y1451000D03*
X109700Y1425900D03*
X91300Y1439000D03*
X128800Y1482000D03*
X159900Y545600D03*
X162700Y622700D03*
X152329Y615065D03*
X171800Y701100D03*
X152096Y1419200D03*
Y1415000D03*
X140500Y1458400D03*
X152100Y1423400D03*
X190800Y439500D03*
G54D53*
X78900Y1498700D03*
Y1523500D03*
X124298Y1883503D03*
Y1908303D03*
X145798Y1151303D03*
Y1126503D03*
G54D71*
X147500Y1437250D03*
X143625Y1444750D03*
X151375D03*
G54D62*
X116175Y846304D03*
X113620D03*
X111060D03*
X108500D03*
X105940D03*
X103380D03*
X100825D03*
Y868504D03*
X103380D03*
X105940D03*
X108500D03*
X111060D03*
X113620D03*
X116175D03*
X121640Y963000D03*
X119080D03*
X116520D03*
X113960D03*
Y985200D03*
X116520D03*
X119080D03*
X121640D03*
X155825Y732304D03*
X158380D03*
X160940D03*
X163500D03*
X166060D03*
X168620D03*
X171175D03*
Y710104D03*
X168620D03*
X166060D03*
X163500D03*
X160940D03*
X158380D03*
X155825D03*
X137340Y959500D03*
X139900D03*
X142460D03*
X145020D03*
X147580D03*
X150140D03*
X152700D03*
X155260D03*
Y981700D03*
X152700D03*
X150140D03*
X147580D03*
X145020D03*
X142460D03*
X139900D03*
X137340D03*
G54D44*
X72000Y473548D03*
Y491452D03*
X90000Y473548D03*
Y491452D03*
X176000Y473048D03*
Y490952D03*
X158000Y473048D03*
Y490952D03*
G54D26*
X24100Y685300D03*
X28900D03*
X74100Y570600D03*
X82000Y702600D03*
X65635Y688306D03*
X70535D03*
X72200Y705400D03*
X67200D03*
X70800Y975800D03*
X64200Y998500D03*
X81398Y1132153D03*
X92300Y872854D03*
X87500D03*
X94000Y957200D03*
X103500Y974200D03*
X129900Y986900D03*
X140400Y566800D03*
X158535Y604079D03*
G54D35*
X83847Y61398D03*
X40000Y294300D03*
X56200Y252800D03*
X73500Y591000D03*
X76600Y986600D03*
X67600Y1025000D03*
X116900Y380100D03*
X91529Y533679D03*
X107100Y986000D03*
Y990800D03*
X94800Y1455500D03*
X106800Y1474500D03*
X165900Y532100D03*
X165700Y553300D03*
X182021Y613535D03*
X160300Y1462500D03*
G54D54*
X71250Y1613297D03*
Y1619703D03*
X130250Y1613297D03*
Y1619703D03*
X101750Y1613297D03*
Y1619703D03*
X157750Y1613297D03*
Y1619703D03*
G54D18*
X27471Y262553D03*
X19721D03*
X23596Y255053D03*
X24925Y305350D03*
X32675D03*
X28800Y312850D03*
X35375Y1649050D03*
X27625D03*
X31500Y1641550D03*
X27292Y1714868D03*
X19542D03*
X23417Y1707368D03*
X58692Y909868D03*
X50942D03*
X54817Y902368D03*
X78752Y1613297D03*
Y1619703D03*
X131525Y722550D03*
X135400Y730050D03*
X137752Y1613297D03*
Y1619703D03*
X109252Y1613297D03*
Y1619703D03*
X141625Y682250D03*
X149375D03*
X145500Y689750D03*
X139275Y722550D03*
X138694Y1422269D03*
X146444D03*
X148025Y1401454D03*
X155775D03*
X151900Y1408954D03*
X165494Y1437469D03*
X173244D03*
X169369Y1444969D03*
X142569Y1429769D03*
X165252Y1613297D03*
Y1619703D03*
G54D27*
X31868Y1089208D03*
Y1096958D03*
X24368Y1093083D03*
X112018Y566991D03*
Y574741D03*
X104518Y570866D03*
X112018Y1255968D03*
Y1263718D03*
X104518Y1259843D03*
G54D63*
X113800Y1397140D03*
Y1399700D03*
Y1402260D03*
X106400D03*
Y1399700D03*
Y1397140D03*
G54D45*
X85400Y544750D03*
X83430D03*
X81465D03*
Y561050D03*
X83430D03*
X85400D03*
X89335Y544750D03*
X87370D03*
Y561050D03*
X89335D03*
X108710Y612629D03*
X110675D03*
X112645D03*
X114615D03*
X116580D03*
X118550D03*
X120520D03*
X122490D03*
X124455D03*
X126425D03*
X128395D03*
X130360D03*
Y646029D03*
X128395D03*
X126425D03*
X124455D03*
X122490D03*
X120520D03*
X118550D03*
X116580D03*
X114615D03*
X112645D03*
X110675D03*
X108710D03*
X153135Y542950D03*
X151170D03*
X149200D03*
X147230D03*
X145265D03*
Y559250D03*
X147230D03*
X149200D03*
X151170D03*
X153135D03*
G54D72*
X142300Y1471800D03*
Y1480800D03*
G54D36*
X67998Y56503D03*
X67398Y71003D03*
X60600Y195000D03*
X61000Y240000D03*
X61600Y211300D03*
X54300Y263300D03*
X58300D03*
X37200Y256900D03*
X62600Y249200D03*
X73700Y543300D03*
X78600Y574500D03*
X73900Y558800D03*
X39000Y581300D03*
X77200Y705900D03*
X77000Y730800D03*
X43400Y896100D03*
X81398Y1126103D03*
X63498Y1123803D03*
X63198Y1142003D03*
X48300Y1755700D03*
X136779Y543071D03*
X116800Y588596D03*
X128900D03*
X91300Y573200D03*
X136679Y557171D03*
X129335Y662029D03*
X133535D03*
X104900Y662200D03*
X115600Y660200D03*
X116300Y670600D03*
X119600Y831800D03*
X111200D03*
X102900Y831796D03*
X121671Y939756D03*
X117300Y939700D03*
X110500D03*
X136000Y947800D03*
X131500D03*
X123300Y1001300D03*
X119300D03*
X114800D03*
X99000Y979700D03*
X135000Y1003200D03*
X123000Y1424200D03*
X127500D03*
X95500Y1464200D03*
X118000Y1424200D03*
X95600Y1423700D03*
X137000Y1501700D03*
X133000D03*
X129000D03*
X125000D03*
X121000D03*
X117000D03*
X113000D03*
X109000D03*
X93500Y1479200D03*
X145300Y582200D03*
X153500Y570000D03*
X151335Y635829D03*
X148435Y653329D03*
X144235D03*
X154500Y702700D03*
X167700Y699600D03*
X158500Y702700D03*
X149000Y949200D03*
X153000D03*
X157000D03*
X145000D03*
X140500Y947800D03*
X139100Y1003100D03*
X156631Y1431081D03*
X160831Y1430281D03*
X152331Y1431081D03*
X148500Y1474100D03*
X165400Y1430200D03*
X151000Y1491200D03*
X146500D03*
X142000D03*
X137900Y1491100D03*
G54D73*
G01X-448201Y-66763D02*
X-480201D01*
G01X-448201Y-82763D02*
Y-162763D01*
G01Y-118263D02*
X752899D01*
G01X-448201Y-162763D02*
X752899D01*
G01X-452201Y-66763D02*
G02I-12000J0D01*
G01X-457351D02*
G02I-6850J0D01*
G01X-464201Y-82763D02*
Y-50763D01*
G01X-448201Y-82763D02*
X752899D01*
G01X-34601D02*
Y-162763D01*
G01X102899Y-82763D02*
Y-162763D01*
G01X217899Y-82763D02*
Y-162763D01*
G01X385399Y-82763D02*
Y-162763D01*
G01X555399Y-82763D02*
Y-162763D01*
G01X752899Y-82763D02*
Y-162763D01*
G01X780899Y-66763D02*
G02I-12000J0D01*
G01X775749D02*
G02I-6850J0D01*
G01X768899Y-82763D02*
Y-50763D01*
G01X784899Y-66763D02*
X752899D01*
G54D19*
X32500Y321300D03*
X33500Y1083600D03*
X22000Y1644300D03*
X21800Y1720700D03*
X23600Y1692800D03*
X60300Y155300D03*
Y163300D03*
Y179300D03*
Y159300D03*
Y175300D03*
X49900Y213400D03*
X61200Y217000D03*
X60300Y199300D03*
X36200Y272300D03*
X74200Y431300D03*
X64400Y577200D03*
X81956Y690465D03*
X84100Y686400D03*
X48800Y916400D03*
X72100Y999800D03*
X52800Y1769800D03*
X91703Y61502D03*
X89200Y71500D03*
X121300Y437500D03*
X129356Y692165D03*
X129256Y688065D03*
Y683665D03*
X116300Y670600D03*
X87396Y848500D03*
Y844100D03*
Y852900D03*
X87400Y857200D03*
Y865700D03*
Y861500D03*
X115300Y1408200D03*
X94700Y1451000D03*
X113100Y1425900D03*
X94700Y1439000D03*
X87700Y1484000D03*
X132200Y1482000D03*
X163300Y545600D03*
X166100Y622700D03*
X155729Y615065D03*
X175200Y701100D03*
X155496Y1419200D03*
Y1415000D03*
X143900Y1458400D03*
X155500Y1423400D03*
X194200Y439500D03*
G54D55*
X48200Y1760300D03*
X98600Y553300D03*
X86800Y537800D03*
X96100D03*
X112900Y603500D03*
X107600Y593700D03*
X170600Y536400D03*
X160900Y536500D03*
G54D37*
X67998Y53103D03*
X67398Y67603D03*
X60600Y191600D03*
X62600Y245800D03*
X61000Y236600D03*
X61600Y207900D03*
X54300Y259900D03*
X58300D03*
X37200Y253500D03*
X73700Y539900D03*
X78600Y571100D03*
X73900Y555400D03*
X39000Y577900D03*
X77200Y702500D03*
X77000Y727400D03*
X43400Y892700D03*
X81398Y1122703D03*
X63498Y1120403D03*
X63198Y1138603D03*
X48300Y1752300D03*
X136779Y539671D03*
X116800Y585196D03*
X128900D03*
X91300Y569800D03*
X136679Y553771D03*
X129335Y658629D03*
X133535D03*
X104900Y658800D03*
X115600Y656800D03*
X116300Y667200D03*
X119600Y828400D03*
X111200D03*
X102900Y828396D03*
X121671Y936356D03*
X117300Y936300D03*
X110500D03*
X136000Y944400D03*
X131500D03*
X123300Y997900D03*
X119300D03*
X114800D03*
X99000Y976300D03*
X135000Y999800D03*
X123000Y1420800D03*
X127500D03*
X118000D03*
X95600Y1420300D03*
X95500Y1460800D03*
X137000Y1498300D03*
X133000D03*
X129000D03*
X125000D03*
X121000D03*
X117000D03*
X113000D03*
X109000D03*
X93500Y1475800D03*
X145300Y578800D03*
X153500Y566600D03*
X151335Y632429D03*
X148435Y649929D03*
X144235D03*
X154500Y699300D03*
X167700Y696200D03*
X158500Y699300D03*
X149000Y945800D03*
X153000D03*
X157000D03*
X145000D03*
X140500Y944400D03*
X139100Y999700D03*
X156631Y1427681D03*
X160831Y1426881D03*
X152331Y1427681D03*
X148500Y1470700D03*
X165400Y1426800D03*
X151000Y1487800D03*
X146500D03*
X142000D03*
X137900Y1487700D03*
G54D64*
X125000Y1409454D03*
X121125Y1401954D03*
X128875D03*
G54D46*
X73403Y606702D03*
Y633502D03*
X122097Y1125298D03*
Y1152098D03*
X98497Y1883198D03*
Y1909998D03*
G54D28*
X32359Y1680500D03*
X60641D03*
G54D74*
G01X-430254Y-152763D02*
Y-135263D01*
G01X-421958D02*
X-430254Y-146055D01*
G01X-420648Y-152763D02*
X-426543Y-141097D01*
G01X-412973Y-152763D02*
Y-135263D01*
X-402929Y-152763D01*
Y-135263D01*
G01X-390451Y-152763D02*
X-392198Y-152471D01*
X-393726Y-151305D01*
X-395036Y-149555D01*
X-395910Y-147513D01*
X-396346Y-145180D01*
Y-142846D01*
X-395910Y-140513D01*
X-395036Y-138471D01*
X-393726Y-136722D01*
X-392198Y-135555D01*
X-390451Y-135263D01*
X-388705Y-135555D01*
X-387176Y-136722D01*
X-385866Y-138471D01*
X-384992Y-140513D01*
X-384556Y-142846D01*
Y-145180D01*
X-384992Y-147513D01*
X-385866Y-149555D01*
X-387176Y-151305D01*
X-388705Y-152471D01*
X-390451Y-152763D01*
G01X-377536D02*
X-368366Y-135263D01*
G01X-377536D02*
X-368366Y-152763D01*
G01X-362001Y-158596D02*
X-348901D01*
G01X-342099Y-152763D02*
Y-135263D01*
X-333803D01*
G01X-336859Y-143721D02*
X-342099D01*
G01X-325910Y-152763D02*
X-320451Y-135263D01*
X-314992Y-152763D01*
G01X-316958Y-146638D02*
X-323945D01*
G01X-307973Y-152763D02*
Y-135263D01*
X-297929Y-152763D01*
Y-135263D01*
G01X-263148Y-136722D02*
X-264458Y-135846D01*
X-265986Y-135263D01*
X-267733D01*
X-269698Y-136138D01*
X-271226Y-137596D01*
X-272318Y-139347D01*
X-273191Y-142263D01*
X-273410Y-144888D01*
X-272973Y-147513D01*
X-272318Y-149263D01*
X-271008Y-151013D01*
X-269479Y-152180D01*
X-267951Y-152763D01*
X-266423D01*
X-264894Y-152180D01*
X-263584Y-151305D01*
X-262492Y-150139D01*
G01X-250451Y-152763D02*
X-252198Y-152471D01*
X-253726Y-151305D01*
X-255036Y-149555D01*
X-255910Y-147513D01*
X-256346Y-145180D01*
Y-142846D01*
X-255910Y-140513D01*
X-255036Y-138471D01*
X-253726Y-136722D01*
X-252198Y-135555D01*
X-250451Y-135263D01*
X-248705Y-135555D01*
X-247176Y-136722D01*
X-245866Y-138471D01*
X-244992Y-140513D01*
X-244556Y-142846D01*
Y-145180D01*
X-244992Y-147513D01*
X-245866Y-149555D01*
X-247176Y-151305D01*
X-248705Y-152471D01*
X-250451Y-152763D01*
G01X-237973D02*
Y-135263D01*
X-227929Y-152763D01*
Y-135263D01*
G01X-215451D02*
Y-152763D01*
G01X-220473Y-135263D02*
X-210429D01*
G01X-202318Y-152763D02*
Y-135263D01*
X-196859D01*
X-195113Y-136138D01*
X-194021Y-137305D01*
X-193584Y-139638D01*
X-194021Y-141972D01*
X-195331Y-143430D01*
X-196859Y-144305D01*
X-202318D01*
G01X-196859D02*
X-193584Y-152763D01*
G01X-180451D02*
X-182198Y-152471D01*
X-183726Y-151305D01*
X-185036Y-149555D01*
X-185910Y-147513D01*
X-186346Y-145180D01*
Y-142846D01*
X-185910Y-140513D01*
X-185036Y-138471D01*
X-183726Y-136722D01*
X-182198Y-135555D01*
X-180451Y-135263D01*
X-178705Y-135555D01*
X-177176Y-136722D01*
X-175866Y-138471D01*
X-174992Y-140513D01*
X-174556Y-142846D01*
Y-145180D01*
X-174992Y-147513D01*
X-175866Y-149555D01*
X-177176Y-151305D01*
X-178705Y-152471D01*
X-180451Y-152763D01*
G01X-167318Y-135263D02*
Y-152763D01*
X-158584D01*
G01X-126205Y-143430D02*
X-125331Y-142555D01*
X-124676Y-141097D01*
X-124239Y-139054D01*
X-124676Y-137305D01*
X-125549Y-136138D01*
X-127078Y-135263D01*
X-132973D01*
Y-152763D01*
X-125768D01*
X-124239Y-151597D01*
X-123366Y-149846D01*
X-122929Y-147805D01*
X-123366Y-145763D01*
X-124676Y-144013D01*
X-126205Y-143430D01*
X-132973D01*
G01X-110451Y-152763D02*
X-112198Y-152471D01*
X-113726Y-151305D01*
X-115036Y-149555D01*
X-115910Y-147513D01*
X-116346Y-145180D01*
Y-142846D01*
X-115910Y-140513D01*
X-115036Y-138471D01*
X-113726Y-136722D01*
X-112198Y-135555D01*
X-110451Y-135263D01*
X-108705Y-135555D01*
X-107176Y-136722D01*
X-105866Y-138471D01*
X-104992Y-140513D01*
X-104556Y-142846D01*
Y-145180D01*
X-104992Y-147513D01*
X-105866Y-149555D01*
X-107176Y-151305D01*
X-108705Y-152471D01*
X-110451Y-152763D01*
G01X-98410D02*
X-92951Y-135263D01*
X-87492Y-152763D01*
G01X-89458Y-146638D02*
X-96445D01*
G01X-79818Y-152763D02*
Y-135263D01*
X-74359D01*
X-72613Y-136138D01*
X-71521Y-137305D01*
X-71084Y-139638D01*
X-71521Y-141972D01*
X-72831Y-143430D01*
X-74359Y-144305D01*
X-79818D01*
G01X-74359D02*
X-71084Y-152763D01*
G01X-62754D02*
Y-135263D01*
X-58388D01*
X-56641Y-136138D01*
X-55331Y-137305D01*
X-54239Y-139054D01*
X-53366Y-141097D01*
X-53148Y-144013D01*
X-53366Y-146930D01*
X-54239Y-148972D01*
X-55331Y-150722D01*
X-56641Y-151888D01*
X-58388Y-152763D01*
X-62754D01*
G01X-282378Y-107763D02*
Y-90263D01*
X-276701Y-104846D01*
X-271024Y-90263D01*
Y-107763D01*
G01X-259201D02*
X-260511Y-107471D01*
X-261821Y-106305D01*
X-262695Y-104263D01*
X-263131Y-101930D01*
X-262695Y-99596D01*
X-261821Y-97555D01*
X-260511Y-96388D01*
X-259201Y-96097D01*
X-257891Y-96388D01*
X-256581Y-97555D01*
X-255708Y-99596D01*
X-255489Y-101930D01*
X-255708Y-104263D01*
X-256581Y-106305D01*
X-257891Y-107471D01*
X-259201Y-107763D01*
G01X-237771Y-90263D02*
Y-107763D01*
G01Y-105139D02*
X-238644Y-106597D01*
X-239955Y-107471D01*
X-241483Y-107763D01*
X-243229Y-107180D01*
X-244539Y-105722D01*
X-245413Y-103972D01*
X-245631Y-101930D01*
X-245413Y-99888D01*
X-244539Y-98138D01*
X-243229Y-96680D01*
X-241483Y-96097D01*
X-239955Y-96388D01*
X-238863Y-96972D01*
X-237771Y-98138D01*
G01X-227476Y-99888D02*
X-220489D01*
X-221144Y-97846D01*
X-222236Y-96680D01*
X-223764Y-96097D01*
X-225293Y-96388D01*
X-226603Y-97263D01*
X-227476Y-99305D01*
X-227913Y-101055D01*
Y-102805D01*
X-227476Y-104555D01*
X-226384Y-106305D01*
X-225074Y-107471D01*
X-223546Y-107763D01*
X-222018Y-107180D01*
X-220489Y-105430D01*
G01X-206701Y-107763D02*
Y-90263D01*
G01X-222441Y169326D02*
Y39370D01*
G01D02*
G03X-214567Y31496I7874J0D01*
G01X-242126Y15000D02*
G03X-227126Y0I15000J0D01*
G01X-242126Y1953504D02*
Y15000D01*
G01X-215453Y19685D02*
G03I-6988J0D01*
G01X-84646Y0D02*
X-227126D01*
G01X-215453Y19685D02*
G03I-6988J0D01*
G01D02*
G03I-6988J0D01*
G01X-214567Y169326D02*
G03X-222441I-3937J0D01*
G01X-214567D02*
G03X-222441I-3937J0D01*
G01Y436255D02*
Y200034D01*
G01D02*
G03X-214567I3937J0D01*
G01X-222441D02*
G03X-214567I3937J0D01*
G01Y436255D02*
G03X-222441I-3937J0D01*
G01X-214567D02*
G03X-222441I-3937J0D01*
G01Y703184D02*
Y466963D01*
G01D02*
G03X-214567I3937J0D01*
G01X-222441D02*
G03X-214567I3937J0D01*
G01Y703184D02*
G03X-222441I-3937J0D01*
G01X-214567D02*
G03X-222441I-3937J0D01*
G01Y970901D02*
Y733892D01*
G01D02*
G03X-214567I3937J0D01*
G01X-222441D02*
G03X-214567I3937J0D01*
G01X-222441Y1234681D02*
Y997672D01*
G01X-214567Y970901D02*
G03X-222441I-3937J0D01*
G01Y997672D02*
G03X-214567I3937J0D01*
G01Y970901D02*
G03X-222441I-3937J0D01*
G01Y997672D02*
G03X-214567I3937J0D01*
G01X-222441Y1501610D02*
Y1265389D01*
G01D02*
G03X-214567I3937J0D01*
G01Y1234681D02*
G03X-222441I-3937J0D01*
G01Y1265389D02*
G03X-214567I3937J0D01*
G01Y1234681D02*
G03X-222441I-3937J0D01*
G01X-214567Y1501610D02*
G03X-222441I-3937J0D01*
G01X-214567D02*
G03X-222441I-3937J0D01*
G01Y1768539D02*
Y1532318D01*
G01D02*
G03X-214567I3937J0D01*
G01X-222441D02*
G03X-214567I3937J0D01*
G01Y1768539D02*
G03X-222441I-3937J0D01*
G01X-214567D02*
G03X-222441I-3937J0D01*
G01Y1799247D02*
G03X-214567I3937J0D01*
G01X-222441D02*
G03X-214567I3937J0D01*
G01X-222441Y1929134D02*
Y1799247D01*
G01X-214567Y1937008D02*
G03X-222441Y1929134I0J-7874D01*
G01X-227126Y1968504D02*
G03X-242126Y1953504I0J-15000D01*
G01X-215453Y1948819D02*
G03I-6988J0D01*
G01X-84638Y1968504D02*
X-227126D01*
G01X-215453Y1948819D02*
G03I-6988J0D01*
G01D02*
G03I-6988J0D01*
G01X-214567Y43307D02*
G03X-210630Y39370I3937J0D01*
G01X-214567Y43307D02*
G03X-210630Y39370I3937J0D01*
G01X-80709D02*
X-210630D01*
G01X-80709D02*
X-210630D01*
G01X-206693Y31496D02*
X-214567D01*
G01X-175984D02*
X-84646D01*
G01X-206693D02*
G03Y39370I0J3937D01*
G01X-175984D02*
G03Y31496I0J-3937D01*
G01X-206693D02*
X-214567D01*
G01X-84646Y0D02*
X-199567D01*
G01X-175984Y31496D02*
X-84646D01*
G01X-206693D02*
G03Y39370I0J3937D01*
G01X-175984D02*
G03Y31496I0J-3937D01*
G01X-214567Y43307D02*
Y1925197D01*
G01Y43307D02*
Y1925197D01*
G01Y149606D02*
Y43307D01*
G01Y149606D02*
Y43272D01*
G01Y1807087D02*
Y161417D01*
G01Y1807087D02*
Y161417D01*
G01Y1818898D02*
Y1925231D01*
G01Y1818898D02*
Y1925231D01*
G01X-210630Y1929134D02*
G03X-214567Y1925197I0J-3937D01*
G01X-210630Y1929134D02*
G03X-214567Y1925197I0J-3937D01*
G01X-210630Y1929134D02*
X-80709D01*
G01X-210630D02*
X-80709D01*
G01X-175984Y1937008D02*
G03Y1929134I0J-3937D01*
G01X-206693D02*
G03Y1937008I0J3937D01*
G01X-175984D02*
G03Y1929134I0J-3937D01*
G01X-206693D02*
G03Y1937008I0J3937D01*
G01X-175984D02*
X-84638D01*
G01X-214567D02*
X-206693D01*
G01X-84638Y1968504D02*
X-199567D01*
G01X-175984Y1937008D02*
X-84638D01*
G01X-214567D02*
X-206693D01*
G01X-76772Y3937D02*
G03X-72835Y0I3937J0D01*
G01X-76772Y35433D02*
G03X-80709Y39370I-3937J0D01*
G01X-76772Y35433D02*
G03X-80709Y39370I-3937J0D01*
G01X-76772Y3937D02*
G03X-72835Y0I3937J0D01*
G01X-11811D02*
X-72835D01*
G01X-11811D02*
X-72835D01*
G01X-76772Y3937D02*
Y35433D01*
G01Y3937D02*
Y35433D01*
G01X-72835Y0D02*
X-11811D01*
G01X-76772Y3937D02*
G03X-72835Y0I3937J0D01*
G01X-84646Y7874D02*
Y0D01*
G01X-76772Y7874D02*
G03X-84646I-3937J0D01*
G01Y31496D02*
G03X-76772I3937J0D01*
G01X-72835Y0D02*
X-11811D01*
G01X-76772Y3937D02*
G03X-72835Y0I3937J0D01*
G01X-84646Y7874D02*
Y0D01*
G01X-76772Y7874D02*
G03X-84646I-3937J0D01*
G01Y31496D02*
G03X-76772I3937J0D01*
G01X-80709Y1929134D02*
G03X-76772Y1933071I0J3937D01*
G01X-80709Y1929134D02*
G03X-76772Y1933071I0J3937D01*
G01D02*
Y1964567D01*
G01Y1933071D02*
Y1964567D01*
G01X-76763Y1937008D02*
G03X-84638I-3937J0D01*
G01X-72835Y1968504D02*
G03X-76772Y1964567I0J-3937D01*
G01X-72835Y1968504D02*
G03X-76772Y1964567I0J-3937D01*
G01X-72835Y1968504D02*
X-11811D01*
G01X-72835D02*
X-11811D01*
G01X-72835D02*
G03X-76772Y1964567I0J-3937D01*
G01X-11811Y1968504D02*
X-72835D01*
G01X-84638Y1960889D02*
Y1968504D01*
G01Y1960889D02*
G03X-76763I3938J0D01*
G01X-72835Y1968504D02*
G03X-76772Y1964567I0J-3937D01*
G01X-11811Y1968504D02*
X-72835D01*
G01X-84638Y1960889D02*
Y1968504D01*
G01Y1960889D02*
G03X-76763I3938J0D01*
G01X-14018Y-107763D02*
Y-90263D01*
X-8778D01*
X-7031Y-91138D01*
X-5721Y-93180D01*
X-5284Y-95513D01*
X-5721Y-97846D01*
X-6813Y-99596D01*
X-8778Y-100472D01*
X-14018D01*
G01X12652Y-91722D02*
X11342Y-90846D01*
X9814Y-90263D01*
X8067D01*
X6102Y-91138D01*
X4574Y-92596D01*
X3482Y-94347D01*
X2609Y-97263D01*
X2390Y-99888D01*
X2827Y-102513D01*
X3482Y-104263D01*
X4792Y-106013D01*
X6321Y-107180D01*
X7849Y-107763D01*
X9377D01*
X10906Y-107180D01*
X12216Y-106305D01*
X13308Y-105139D01*
G01X27095Y-98430D02*
X27969Y-97555D01*
X28624Y-96097D01*
X29061Y-94054D01*
X28624Y-92305D01*
X27751Y-91138D01*
X26222Y-90263D01*
X20327D01*
Y-107763D01*
X27532D01*
X29061Y-106597D01*
X29934Y-104846D01*
X30371Y-102805D01*
X29934Y-100763D01*
X28624Y-99013D01*
X27095Y-98430D01*
X20327D01*
G01X36299Y-113596D02*
X49399D01*
G01X55327Y-107763D02*
Y-90263D01*
X65371Y-107763D01*
Y-90263D01*
G01X77849Y-107763D02*
X76102Y-107471D01*
X74574Y-106305D01*
X73264Y-104555D01*
X72390Y-102513D01*
X71954Y-100180D01*
Y-97846D01*
X72390Y-95513D01*
X73264Y-93471D01*
X74574Y-91722D01*
X76102Y-90555D01*
X77849Y-90263D01*
X79595Y-90555D01*
X81124Y-91722D01*
X82434Y-93471D01*
X83308Y-95513D01*
X83744Y-97846D01*
Y-100180D01*
X83308Y-102513D01*
X82434Y-104555D01*
X81124Y-106305D01*
X79595Y-107471D01*
X77849Y-107763D01*
G01X-901Y-152763D02*
Y-135263D01*
X-3521Y-138763D01*
G01Y-152763D02*
X1719D01*
G01X12451Y-138180D02*
X13761Y-136430D01*
X15289Y-135555D01*
X17036Y-135263D01*
X19219Y-135846D01*
X20747Y-137305D01*
X21184Y-139054D01*
X20966Y-140805D01*
X20092Y-142263D01*
X15726Y-145180D01*
X13761Y-147221D01*
X12451Y-150139D01*
X12014Y-152763D01*
X21184D01*
G01X36719D02*
Y-135263D01*
X28640Y-147805D01*
X39558D01*
G01X46796Y-149263D02*
X48105Y-151305D01*
X49852Y-152471D01*
X51817Y-152763D01*
X53564Y-152471D01*
X55311Y-151013D01*
X56402Y-149263D01*
X56621Y-147513D01*
X56184Y-145472D01*
X54656Y-144013D01*
X53127Y-143430D01*
X51162D01*
G01X53127D02*
X54437Y-142555D01*
X55529Y-141097D01*
X55966Y-139347D01*
X55529Y-137596D01*
X54437Y-136138D01*
X52472Y-135263D01*
X50507Y-135555D01*
X48542Y-136722D01*
G01X64296Y-149263D02*
X65605Y-151305D01*
X67352Y-152471D01*
X69317Y-152763D01*
X71064Y-152471D01*
X72811Y-151013D01*
X73902Y-149263D01*
X74121Y-147513D01*
X73684Y-145472D01*
X72156Y-144013D01*
X70627Y-143430D01*
X68662D01*
G01X70627D02*
X71937Y-142555D01*
X73029Y-141097D01*
X73466Y-139347D01*
X73029Y-137596D01*
X71937Y-136138D01*
X69972Y-135263D01*
X68007Y-135555D01*
X66042Y-136722D01*
G01X-11811Y0D02*
G03X-7874Y3937I0J3937D01*
G01X-11811Y0D02*
G03X-7874Y3937I0J3937D01*
G01Y43110D02*
Y3937D01*
G01Y43110D02*
Y3937D01*
G01X0D02*
G03X3937Y0I3937J0D01*
G01X0Y3937D02*
G03X3937Y0I3937J0D01*
G01X0Y3937D02*
Y43110D01*
G01Y3937D02*
Y43110D01*
G01X64961Y0D02*
X3937D01*
G01X64961D02*
X3937D01*
G01X0Y3937D02*
G03X3937Y0I3937J0D01*
G01X0Y1964567D02*
Y3937D01*
G01X3937Y0D02*
X64961D01*
G01X-7874Y3937D02*
Y1964567D01*
G01X-11811Y0D02*
G03X-7874Y3937I0J3937D01*
G01X0Y11811D02*
G03X-7874I-3937J0D01*
G01Y42520D02*
G03X0I3937J0D01*
G01Y3937D02*
G03X3937Y0I3937J0D01*
G01X0Y1964567D02*
Y3937D01*
G01X3937Y0D02*
X64961D01*
G01X-7874Y3937D02*
Y1964567D01*
G01X-11811Y0D02*
G03X-7874Y3937I0J3937D01*
G01X0Y11811D02*
G03X-7874I-3937J0D01*
G01Y42520D02*
G03X0I3937J0D01*
G01X-7874Y93110D02*
Y43110D01*
G01Y93110D02*
Y43110D01*
G01X0D02*
Y93110D01*
G01Y43110D02*
Y93110D01*
G01X-7874Y214764D02*
Y93110D01*
G01Y214764D02*
Y93110D01*
G01X0D02*
Y214764D01*
G01Y93110D02*
Y214764D01*
G01X-7874Y226968D02*
Y214764D01*
G01Y226968D02*
Y214764D01*
G01Y342461D02*
Y226968D01*
G01Y342461D02*
Y226968D01*
G01X0Y226969D02*
Y342461D01*
G01Y226969D02*
Y342461D01*
G01Y214764D02*
Y226969D01*
G01Y214764D02*
Y226969D01*
G01Y278740D02*
G03X-7874I-3937J0D01*
G01X0D02*
G03X-7874I-3937J0D01*
G01Y354665D02*
Y342461D01*
G01Y354665D02*
Y342461D01*
G01X0D02*
Y354665D01*
G01Y342461D02*
Y354665D01*
G01X-7874Y309449D02*
G03X0I3937J0D01*
G01X-7874D02*
G03X0I3937J0D01*
G01X-7874Y476339D02*
Y354665D01*
G01Y476339D02*
Y354665D01*
G01X0D02*
Y476339D01*
G01Y354665D02*
Y476339D01*
G01X-7874Y526339D02*
Y476339D01*
G01Y526339D02*
Y476339D01*
G01X0D02*
Y526339D01*
G01Y476339D02*
Y526339D01*
G01X-7874Y736181D02*
Y526339D01*
G01Y736181D02*
Y526339D01*
G01X0D02*
Y736181D01*
G01Y526339D02*
Y736181D01*
G01Y545669D02*
G03X-7874I-3937J0D01*
G01X0D02*
G03X-7874I-3937J0D01*
G01Y576378D02*
G03X0I3937J0D01*
G01X-7874D02*
G03X0I3937J0D01*
G01X-7874Y786181D02*
Y736181D01*
G01Y786181D02*
Y736181D01*
G01X0D02*
Y786181D01*
G01Y736181D02*
Y786181D01*
G01X-7874Y907815D02*
Y786181D01*
G01Y907815D02*
Y786181D01*
G01X0D02*
Y907815D01*
G01Y786181D02*
Y907815D01*
G01X-7874Y862205D02*
G03X0I3937J0D01*
G01Y831496D02*
G03X-7874I-3937J0D01*
G01Y862205D02*
G03X0I3937J0D01*
G01Y831496D02*
G03X-7874I-3937J0D01*
G01Y920020D02*
Y907815D01*
G01Y920020D02*
Y907815D01*
G01X0D02*
Y920020D01*
G01Y907815D02*
Y920020D01*
G01X-7874Y1048484D02*
Y920020D01*
G01Y1048484D02*
Y920020D01*
G01X0D02*
Y1048484D01*
G01Y920020D02*
Y1048484D01*
G01X-7874Y1060689D02*
Y1048484D01*
G01Y1060689D02*
Y1048484D01*
G01Y1182323D02*
Y1060689D01*
G01Y1182323D02*
Y1060689D01*
G01X0D02*
Y1182323D01*
G01Y1060689D02*
Y1182323D01*
G01Y1048484D02*
Y1060689D01*
G01Y1048484D02*
Y1060689D01*
G01Y1106299D02*
G03X-7874I-3937J0D01*
G01X0D02*
G03X-7874I-3937J0D01*
G01Y1137008D02*
G03X0I3937J0D01*
G01X-7874D02*
G03X0I3937J0D01*
G01X-7874Y1232323D02*
Y1182323D01*
G01Y1232323D02*
Y1182323D01*
G01X0D02*
Y1232323D01*
G01Y1182323D02*
Y1232323D01*
G01X-7874Y1442165D02*
Y1232323D01*
G01Y1442165D02*
Y1232323D01*
G01X0D02*
Y1442165D01*
G01Y1232323D02*
Y1442165D01*
G01X-7874Y1422835D02*
G03X0I3937J0D01*
G01Y1392126D02*
G03X-7874I-3937J0D01*
G01Y1422835D02*
G03X0I3937J0D01*
G01Y1392126D02*
G03X-7874I-3937J0D01*
G01Y1492165D02*
Y1442165D01*
G01Y1492165D02*
Y1442165D01*
G01X0D02*
Y1492165D01*
G01Y1442165D02*
Y1492165D01*
G01X-7874Y1613839D02*
Y1492165D01*
G01Y1613839D02*
Y1492165D01*
G01X0D02*
Y1613839D01*
G01Y1492165D02*
Y1613839D01*
G01X-7874Y1626043D02*
Y1613839D01*
G01Y1626043D02*
Y1613839D01*
G01Y1741535D02*
Y1626043D01*
G01Y1741535D02*
Y1626043D01*
G01X0D02*
Y1741535D01*
G01Y1626043D02*
Y1741535D01*
G01Y1613839D02*
Y1626043D01*
G01Y1613839D02*
Y1626043D01*
G01Y1659055D02*
G03X-7874I-3937J0D01*
G01X0D02*
G03X-7874I-3937J0D01*
G01Y1689764D02*
G03X0I3937J0D01*
G01X-7874D02*
G03X0I3937J0D01*
G01X-7874Y1753740D02*
Y1741535D01*
G01Y1753740D02*
Y1741535D01*
G01Y1875394D02*
Y1753740D01*
G01Y1875394D02*
Y1753740D01*
G01X0D02*
Y1875394D01*
G01Y1753740D02*
Y1875394D01*
G01Y1741535D02*
Y1753740D01*
G01Y1741535D02*
Y1753740D01*
G01X-7874Y1925394D02*
Y1875394D01*
G01Y1925394D02*
Y1875394D01*
G01X0D02*
Y1925394D01*
G01Y1875394D02*
Y1925394D01*
G01X-7874Y1964567D02*
Y1925394D01*
G01Y1964567D02*
Y1925394D01*
G01X0D02*
Y1964567D01*
G01Y1925394D02*
Y1964567D01*
G01Y1925984D02*
G03X-7874I-3937J0D01*
G01X0D02*
G03X-7874I-3937J0D01*
G01Y1964567D02*
G03X-11811Y1968504I-3937J0D01*
G01X-7874Y1964567D02*
G03X-11811Y1968504I-3937J0D01*
G01X3937D02*
G03X0Y1964567I0J-3937D01*
G01X3937Y1968504D02*
G03X0Y1964567I0J-3937D01*
G01X3937Y1968504D02*
X64961D01*
G01X3937D02*
X64961D01*
G01X3937D02*
G03X0Y1964567I0J-3937D01*
G01X64961Y1968504D02*
X3937D01*
G01X-7874Y1964567D02*
G03X-11811Y1968504I-3937J0D01*
G01X-7874Y1956693D02*
G03X0I3937J0D01*
G01X3937Y1968504D02*
G03X0Y1964567I0J-3937D01*
G01X64961Y1968504D02*
X3937D01*
G01X-7874Y1964567D02*
G03X-11811Y1968504I-3937J0D01*
G01X-7874Y1956693D02*
G03X0I3937J0D01*
G01X168110Y31496D02*
X76763D01*
G01X72835Y39370D02*
G03X68898Y35433I0J-3937D01*
G01X72835Y39370D02*
G03X68898Y35433I0J-3937D01*
G01X64961Y0D02*
G03X68898Y3937I0J3937D01*
G01X64961Y0D02*
G03X68898Y3937I0J3937D01*
G01Y35433D02*
Y3937D01*
G01Y35433D02*
Y3937D01*
G01X202756Y39370D02*
X72835D01*
G01X202756D02*
X72835D01*
G01D02*
X202756D01*
G01X72835D02*
G03X68898Y35433I0J-3937D01*
G01Y3937D02*
Y35485D01*
G01X64961Y0D02*
G03X68898Y3937I0J3937D01*
G01X76763D02*
G03X80700Y0I3937J0D01*
G01X76763Y7615D02*
Y3937D01*
G01X80700Y0D02*
X340551D01*
G01X168110Y31496D02*
X76763D01*
G01Y7615D02*
G03X68889I-3937J0D01*
G01Y31496D02*
G03X76763I3937J0D01*
G01X72835Y39370D02*
X202756D01*
G01X72835D02*
G03X68898Y35433I0J-3937D01*
G01Y3937D02*
Y35485D01*
G01X64961Y0D02*
G03X68898Y3937I0J3937D01*
G01X76763D02*
G03X80700Y0I3937J0D01*
G01X76763Y7615D02*
Y3937D01*
G01X80700Y0D02*
X340551D01*
G01X168110Y31496D02*
X76763D01*
G01Y7615D02*
G03X68889I-3937J0D01*
G01Y31496D02*
G03X76763I3937J0D01*
G01X68898Y1933071D02*
G03X72835Y1929134I3937J0D01*
G01X68898Y1933071D02*
G03X72835Y1929134I3937J0D01*
G01D02*
X202756D01*
G01X72835D02*
X202756D01*
G01X68898Y1964567D02*
Y1933071D01*
G01Y1964567D02*
Y1933071D01*
G01D02*
Y1964567D01*
G01Y1933071D02*
G03X72835Y1929134I3937J0D01*
G01X202756D02*
X72835D01*
G01X68898Y1933071D02*
Y1964567D01*
G01Y1933071D02*
G03X72835Y1929134I3937J0D01*
G01X202756D02*
X72835D01*
G01X68898Y1964567D02*
G03X64961Y1968504I-3937J0D01*
G01X68898Y1964567D02*
G03X64961Y1968504I-3937J0D01*
G01X68898Y1964567D02*
G03X64961Y1968504I-3937J0D01*
G01X109377D02*
X80709D01*
G01D02*
G03X76772Y1964567I0J-3937D01*
G01Y1960630D02*
Y1964567D01*
G01X168110Y1937008D02*
X76772D01*
G01X68898Y1960630D02*
G03X76772I3937J0D01*
G01Y1937008D02*
G03X68898I-3937J0D01*
G01Y1964567D02*
G03X64961Y1968504I-3937J0D01*
G01X109377D02*
X80709D01*
G01D02*
G03X76772Y1964567I0J-3937D01*
G01Y1960630D02*
Y1964567D01*
G01X168110Y1937008D02*
X76772D01*
G01X68898Y1960630D02*
G03X76772I3937J0D01*
G01Y1937008D02*
G03X68898I-3937J0D01*
G01X128690Y-90263D02*
X134149Y-107763D01*
X139608Y-90263D01*
G01X156016Y-107763D02*
X147282D01*
Y-90263D01*
X156016D01*
G01X152522Y-98721D02*
X147282D01*
G01X164782Y-107763D02*
Y-90263D01*
X170241D01*
X171987Y-91138D01*
X173079Y-92305D01*
X173516Y-94638D01*
X173079Y-96972D01*
X171769Y-98430D01*
X170241Y-99305D01*
X164782D01*
G01X170241D02*
X173516Y-107763D01*
G01X186649Y-108346D02*
X186212Y-108055D01*
Y-107471D01*
X186649Y-107180D01*
X187086Y-107471D01*
Y-108055D01*
X186649Y-108346D01*
G01X118011Y1968504D02*
X142520D01*
G01X109377D02*
X110137D01*
G01D02*
G03X118011I3937J0D01*
G01X110137D02*
G03X118011I3937J0D01*
G01X147501Y-138180D02*
X148811Y-136430D01*
X150339Y-135555D01*
X152086Y-135263D01*
X154269Y-135846D01*
X155797Y-137305D01*
X156234Y-139054D01*
X156016Y-140805D01*
X155142Y-142263D01*
X150776Y-145180D01*
X148811Y-147221D01*
X147501Y-150139D01*
X147064Y-152763D01*
X156234D01*
G01X163690D02*
X169149Y-135263D01*
X174608Y-152763D01*
G01X172642Y-146638D02*
X165655D01*
G01X168110Y31496D02*
G03Y39370I0J3937D01*
G01Y31496D02*
G03Y39370I0J3937D01*
G01Y1929134D02*
G03Y1937008I0J3937D01*
G01Y1929134D02*
G03Y1937008I0J3937D01*
G01X340559Y1968504D02*
X142520D01*
G01X340559D02*
X142520D01*
G01X202756Y39370D02*
G03X206693Y43307I0J3937D01*
G01X202756Y39370D02*
G03X206693Y43307I0J3937D01*
G01X202756Y39370D02*
G03X206693Y43307I0J3937D01*
G01X218504Y39370D02*
X348425D01*
G01X214567Y43307D02*
G03X218504Y39370I3937J0D01*
G01X222441Y31496D02*
X198819D01*
G01X222441D02*
G03Y39370I0J3937D01*
G01X198819D02*
G03Y31496I0J-3937D01*
G01X202756Y39370D02*
G03X206693Y43307I0J3937D01*
G01X218504Y39370D02*
X348425D01*
G01X214567Y43307D02*
G03X218504Y39370I3937J0D01*
G01X222441Y31496D02*
X198819D01*
G01X222441D02*
G03Y39370I0J3937D01*
G01X198819D02*
G03Y31496I0J-3937D01*
G01X214567Y161417D02*
Y43307D01*
G01X206693Y1925197D02*
Y43307D01*
G01Y1925197D02*
Y43307D01*
G01Y161417D02*
Y1807087D01*
G01X214567D02*
Y161417D01*
G01Y169291D02*
G03X206693I-3937J0D01*
G01Y161417D02*
Y1807087D01*
G01X214567D02*
Y161417D01*
G01Y169291D02*
G03X206693I-3937J0D01*
G01Y200000D02*
G03X214567I3937J0D01*
G01X206693D02*
G03X214567I3937J0D01*
G01Y436220D02*
G03X206693I-3937J0D01*
G01X214567D02*
G03X206693I-3937J0D01*
G01Y466929D02*
G03X214567I3937J0D01*
G01X206693D02*
G03X214567I3937J0D01*
G01Y703149D02*
G03X206693I-3937J0D01*
G01X214567D02*
G03X206693I-3937J0D01*
G01Y733858D02*
G03X214567I3937J0D01*
G01X206693D02*
G03X214567I3937J0D01*
G01Y970867D02*
G03X206693I-3937J0D01*
G01Y997637D02*
G03X214567I3937J0D01*
G01Y970867D02*
G03X206693I-3937J0D01*
G01Y997637D02*
G03X214567I3937J0D01*
G01X206693Y1265355D02*
G03X214567I3937J0D01*
G01Y1234646D02*
G03X206693I-3937J0D01*
G01Y1265355D02*
G03X214567I3937J0D01*
G01Y1234646D02*
G03X206693I-3937J0D01*
G01X214567Y1501575D02*
G03X206693I-3937J0D01*
G01X214567D02*
G03X206693I-3937J0D01*
G01Y1532284D02*
G03X214567I3937J0D01*
G01X206693D02*
G03X214567I3937J0D01*
G01Y1768504D02*
G03X206693I-3937J0D01*
G01X214567D02*
G03X206693I-3937J0D01*
G01X214567Y1807087D02*
Y1925197D01*
G01X206693Y1799213D02*
G03X214567I3937J0D01*
G01X206693D02*
G03X214567I3937J0D01*
G01X206693Y1925197D02*
G03X202756Y1929134I-3937J0D01*
G01X206693Y1925197D02*
G03X202756Y1929134I-3937J0D01*
G01X206693Y1925197D02*
G03X202756Y1929134I-3937J0D01*
G01X218504D02*
G03X214567Y1925197I0J-3937D01*
G01X348425Y1929134D02*
X218504D01*
G01X198819Y1937008D02*
G03Y1929134I0J-3937D01*
G01X222441D02*
G03Y1937008I0J3937D01*
G01X206693Y1925197D02*
G03X202756Y1929134I-3937J0D01*
G01X218504D02*
G03X214567Y1925197I0J-3937D01*
G01X348425Y1929134D02*
X218504D01*
G01X198819Y1937008D02*
G03Y1929134I0J-3937D01*
G01X222441D02*
G03Y1937008I0J3937D01*
G01X198819D02*
X222441D01*
G01X198819D02*
X222441D01*
G01X253482Y-90263D02*
Y-107763D01*
X262216D01*
G01X279279D02*
Y-96097D01*
G01Y-98138D02*
X278406Y-96972D01*
X277095Y-96388D01*
X275567Y-96097D01*
X274039Y-96680D01*
X272729Y-97846D01*
X271855Y-99596D01*
X271419Y-101930D01*
X271855Y-104263D01*
X272729Y-106013D01*
X274039Y-107180D01*
X275567Y-107763D01*
X277095Y-107471D01*
X278406Y-106597D01*
X279279Y-105430D01*
G01X288264Y-113013D02*
X289574Y-113596D01*
X291321Y-113013D01*
X292412Y-111847D01*
X293286Y-110388D01*
X294595Y-105722D01*
X297434Y-96097D01*
G01X290447D02*
X294595Y-105722D01*
G01X307074Y-99888D02*
X314061D01*
X313406Y-97846D01*
X312314Y-96680D01*
X310786Y-96097D01*
X309257Y-96388D01*
X307947Y-97263D01*
X307074Y-99305D01*
X306637Y-101055D01*
Y-102805D01*
X307074Y-104555D01*
X308166Y-106305D01*
X309476Y-107471D01*
X311004Y-107763D01*
X312532Y-107180D01*
X314061Y-105430D01*
G01X324792Y-107763D02*
Y-96097D01*
G01Y-98430D02*
X325884Y-97263D01*
X326976Y-96388D01*
X328504Y-96097D01*
X329595Y-96388D01*
X330906Y-97263D01*
G01X342074Y-105722D02*
X343166Y-106888D01*
X344694Y-107763D01*
X346004D01*
X347314Y-107180D01*
X348187Y-106305D01*
X348624Y-105139D01*
X348406Y-103388D01*
X347532Y-102513D01*
X343602Y-100763D01*
X342729Y-98721D01*
X343166Y-97263D01*
X344039Y-96388D01*
X345349Y-96097D01*
X346659Y-96388D01*
X347969Y-97263D01*
G01X275349Y-135263D02*
Y-152763D01*
G01X270327Y-135263D02*
X280371D01*
G01X288264Y-150430D02*
X290011Y-151888D01*
X291976Y-152763D01*
X293722D01*
X295469Y-151888D01*
X296779Y-150430D01*
X297434Y-148388D01*
X296997Y-146347D01*
X295906Y-144596D01*
X293941Y-143430D01*
X291321Y-142846D01*
X289792Y-141680D01*
X289137Y-139638D01*
X289574Y-137596D01*
X290666Y-136138D01*
X292194Y-135263D01*
X293722D01*
X295251Y-135846D01*
X296561Y-137305D01*
G01X304672Y-152763D02*
Y-135263D01*
X310349Y-149846D01*
X316026Y-135263D01*
Y-152763D01*
G01X323046D02*
Y-135263D01*
X327412D01*
X329159Y-136138D01*
X330469Y-137305D01*
X331561Y-139054D01*
X332434Y-141097D01*
X332652Y-144013D01*
X332434Y-146930D01*
X331561Y-148972D01*
X330469Y-150722D01*
X329159Y-151888D01*
X327412Y-152763D01*
X323046D01*
G01X253150Y31496D02*
X344488D01*
G01X253150Y39370D02*
G03Y31496I0J-3937D01*
G01D02*
X344488D01*
G01X253150Y39370D02*
G03Y31496I0J-3937D01*
G01Y1937008D02*
G03Y1929134I0J-3937D01*
G01Y1937008D02*
G03Y1929134I0J-3937D01*
G01Y1937008D02*
X344496D01*
G01X253150D02*
X344496D01*
G01X340551Y0D02*
G03X344488Y3937I0J3937D01*
G01X340551Y0D02*
G03X344488Y3937I0J3937D01*
G01X344496Y1964567D02*
G03X340559Y1968504I-3937J0D01*
G01X344496Y1964567D02*
G03X340559Y1968504I-3937J0D01*
G01X356299Y0D02*
X417323D01*
G01X352362Y3937D02*
G03X356299Y0I3937J0D01*
G01X352362Y35433D02*
Y3937D01*
G01Y35433D02*
G03X348425Y39370I-3937J0D01*
G01X344488Y7874D02*
Y3937D01*
G01X352362Y7874D02*
G03X344488I-3937J0D01*
G01Y31496D02*
G03X352362I3937J0D01*
G01X356299Y0D02*
X417323D01*
G01X352362Y3937D02*
G03X356299Y0I3937J0D01*
G01X352362Y35433D02*
Y3937D01*
G01Y35433D02*
G03X348425Y39370I-3937J0D01*
G01X344488Y7874D02*
Y3937D01*
G01X352362Y7874D02*
G03X344488I-3937J0D01*
G01Y31496D02*
G03X352362I3937J0D01*
G01X348425Y1929134D02*
G03X352362Y1933071I0J3937D01*
G01Y1964567D02*
Y1933071D01*
G01X348425Y1929134D02*
G03X352362Y1933071I0J3937D01*
G01Y1964567D02*
Y1933071D01*
G01X356299Y1968504D02*
G03X352362Y1964567I0J-3937D01*
G01X417323Y1968504D02*
X356299D01*
G01X344496Y1960889D02*
Y1964567D01*
G01Y1960889D02*
G03X352370I3937J0D01*
G01Y1937008D02*
G03X344496I-3937J0D01*
G01X356299Y1968504D02*
G03X352362Y1964567I0J-3937D01*
G01X417323Y1968504D02*
X356299D01*
G01X344496Y1960889D02*
Y1964567D01*
G01Y1960889D02*
G03X352370I3937J0D01*
G01Y1937008D02*
G03X344496I-3937J0D01*
G01X404346Y-107763D02*
Y-90263D01*
X408712D01*
X410459Y-91138D01*
X411769Y-92305D01*
X412861Y-94054D01*
X413734Y-96097D01*
X413952Y-99013D01*
X413734Y-101930D01*
X412861Y-103972D01*
X411769Y-105722D01*
X410459Y-106888D01*
X408712Y-107763D01*
X404346D01*
G01X423374Y-99888D02*
X430361D01*
X429706Y-97846D01*
X428614Y-96680D01*
X427086Y-96097D01*
X425557Y-96388D01*
X424247Y-97263D01*
X423374Y-99305D01*
X422937Y-101055D01*
Y-102805D01*
X423374Y-104555D01*
X424466Y-106305D01*
X425776Y-107471D01*
X427304Y-107763D01*
X428832Y-107180D01*
X430361Y-105430D01*
G01X440874Y-105722D02*
X441966Y-106888D01*
X443494Y-107763D01*
X444804D01*
X446114Y-107180D01*
X446987Y-106305D01*
X447424Y-105139D01*
X447206Y-103388D01*
X446332Y-102513D01*
X442402Y-100763D01*
X441529Y-98721D01*
X441966Y-97263D01*
X442839Y-96388D01*
X444149Y-96097D01*
X445459Y-96388D01*
X446769Y-97263D01*
G01X461649Y-96097D02*
Y-107763D01*
G01Y-91430D02*
X461212Y-91138D01*
Y-90555D01*
X461649Y-90263D01*
X462086Y-90555D01*
Y-91138D01*
X461649Y-91430D01*
G01X476092Y-112138D02*
X477621Y-113305D01*
X479367Y-113596D01*
X480895Y-113305D01*
X482206Y-111847D01*
X483079Y-109805D01*
Y-96097D01*
G01Y-98430D02*
X482206Y-97263D01*
X480895Y-96388D01*
X479367Y-96097D01*
X477621Y-96680D01*
X476529Y-97846D01*
X475655Y-99888D01*
X475219Y-101930D01*
X475437Y-103680D01*
X476311Y-105722D01*
X477621Y-107180D01*
X479367Y-107763D01*
X480677Y-107471D01*
X482206Y-106305D01*
X483079Y-105139D01*
G01X492937Y-107763D02*
Y-96097D01*
G01Y-99013D02*
X493811Y-97555D01*
X495121Y-96388D01*
X496867Y-96097D01*
X498395Y-96388D01*
X499706Y-97555D01*
X500361Y-99596D01*
Y-107763D01*
G01X510874Y-99888D02*
X517861D01*
X517206Y-97846D01*
X516114Y-96680D01*
X514586Y-96097D01*
X513057Y-96388D01*
X511747Y-97263D01*
X510874Y-99305D01*
X510437Y-101055D01*
Y-102805D01*
X510874Y-104555D01*
X511966Y-106305D01*
X513276Y-107471D01*
X514804Y-107763D01*
X516332Y-107180D01*
X517861Y-105430D01*
G01X528592Y-107763D02*
Y-96097D01*
G01Y-98430D02*
X529684Y-97263D01*
X530776Y-96388D01*
X532304Y-96097D01*
X533395Y-96388D01*
X534706Y-97263D01*
G01X429722Y-152763D02*
Y-135263D01*
X435399Y-149846D01*
X441076Y-135263D01*
Y-152763D01*
G01X452899D02*
X451152Y-152471D01*
X449624Y-151305D01*
X448314Y-149555D01*
X447440Y-147513D01*
X447004Y-145180D01*
Y-142846D01*
X447440Y-140513D01*
X448314Y-138471D01*
X449624Y-136722D01*
X451152Y-135555D01*
X452899Y-135263D01*
X454645Y-135555D01*
X456174Y-136722D01*
X457484Y-138471D01*
X458358Y-140513D01*
X458794Y-142846D01*
Y-145180D01*
X458358Y-147513D01*
X457484Y-149555D01*
X456174Y-151305D01*
X454645Y-152471D01*
X452899Y-152763D01*
G01X465814Y-150430D02*
X467561Y-151888D01*
X469526Y-152763D01*
X471272D01*
X473019Y-151888D01*
X474329Y-150430D01*
X474984Y-148388D01*
X474547Y-146347D01*
X473456Y-144596D01*
X471491Y-143430D01*
X468871Y-142846D01*
X467342Y-141680D01*
X466687Y-139638D01*
X467124Y-137596D01*
X468216Y-136138D01*
X469744Y-135263D01*
X471272D01*
X472801Y-135846D01*
X474111Y-137305D01*
G01X483314Y-150430D02*
X485061Y-151888D01*
X487026Y-152763D01*
X488772D01*
X490519Y-151888D01*
X491829Y-150430D01*
X492484Y-148388D01*
X492047Y-146347D01*
X490956Y-144596D01*
X488991Y-143430D01*
X486371Y-142846D01*
X484842Y-141680D01*
X484187Y-139638D01*
X484624Y-137596D01*
X485716Y-136138D01*
X487244Y-135263D01*
X488772D01*
X490301Y-135846D01*
X491611Y-137305D01*
G01X509766Y-152763D02*
X501032D01*
Y-135263D01*
X509766D01*
G01X506272Y-143721D02*
X501032D01*
G01X429134Y3937D02*
G03X433071Y0I3937J0D01*
G01X429134Y1964567D02*
Y3937D01*
G01X433071Y0D02*
X494095D01*
G01X421260Y3937D02*
Y1964567D01*
G01X417323Y0D02*
G03X421260Y3937I0J3937D01*
G01X429134Y11811D02*
G03X421260I-3937J0D01*
G01Y42520D02*
G03X429134I3937J0D01*
G01Y3937D02*
G03X433071Y0I3937J0D01*
G01X429134Y1964567D02*
Y3937D01*
G01X433071Y0D02*
X494095D01*
G01X421260Y3937D02*
Y1964567D01*
G01X417323Y0D02*
G03X421260Y3937I0J3937D01*
G01X429134Y11811D02*
G03X421260I-3937J0D01*
G01Y42520D02*
G03X429134I3937J0D01*
G01Y278740D02*
G03X421260I-3937J0D01*
G01X429134D02*
G03X421260I-3937J0D01*
G01Y309449D02*
G03X429134I3937J0D01*
G01X421260D02*
G03X429134I3937J0D01*
G01Y545669D02*
G03X421260I-3937J0D01*
G01X429134D02*
G03X421260I-3937J0D01*
G01Y576378D02*
G03X429134I3937J0D01*
G01X421260D02*
G03X429134I3937J0D01*
G01X421260Y862205D02*
G03X429134I3937J0D01*
G01Y831496D02*
G03X421260I-3937J0D01*
G01Y862205D02*
G03X429134I3937J0D01*
G01Y831496D02*
G03X421260I-3937J0D01*
G01X429134Y1106299D02*
G03X421260I-3937J0D01*
G01X429134D02*
G03X421260I-3937J0D01*
G01Y1137008D02*
G03X429134I3937J0D01*
G01X421260D02*
G03X429134I3937J0D01*
G01X421260Y1422835D02*
G03X429134I3937J0D01*
G01Y1392126D02*
G03X421260I-3937J0D01*
G01Y1422835D02*
G03X429134I3937J0D01*
G01Y1392126D02*
G03X421260I-3937J0D01*
G01X429134Y1659055D02*
G03X421260I-3937J0D01*
G01X429134D02*
G03X421260I-3937J0D01*
G01Y1689764D02*
G03X429134I3937J0D01*
G01X421260D02*
G03X429134I3937J0D01*
G01Y1925984D02*
G03X421260I-3937J0D01*
G01X429134D02*
G03X421260I-3937J0D01*
G01X433071Y1968504D02*
G03X429134Y1964567I0J-3937D01*
G01X494095Y1968504D02*
X433071D01*
G01X421260Y1964567D02*
G03X417323Y1968504I-3937J0D01*
G01X421260Y1956693D02*
G03X429134I3937J0D01*
G01X433071Y1968504D02*
G03X429134Y1964567I0J-3937D01*
G01X494095Y1968504D02*
X433071D01*
G01X421260Y1964567D02*
G03X417323Y1968504I-3937J0D01*
G01X421260Y1956693D02*
G03X429134I3937J0D01*
G01X433071Y1968504D02*
G03X429134Y1964567I0J-3937D01*
G01X421260D02*
G03X417323Y1968504I-3937J0D01*
G01X494095Y0D02*
G03X498032Y3937I0J3937D01*
G01X494095Y0D02*
G03X498032Y3937I0J3937D01*
G01Y1964567D02*
G03X494095Y1968504I-3937J0D01*
G01X498032Y1964567D02*
G03X494095Y1968504I-3937J0D01*
G01X501969Y39370D02*
X631890D01*
G01X501969D02*
G03X498032Y35433I0J-3937D01*
G01Y3937D02*
Y35433D01*
G01X505897Y0D02*
X648386D01*
G01X505897Y7615D02*
Y0D01*
G01X597244Y31496D02*
X505897D01*
G01Y7615D02*
G03X498023I-3937J0D01*
G01Y31496D02*
G03X505897I3937J0D01*
G01X501969Y39370D02*
X631890D01*
G01X501969D02*
G03X498032Y35433I0J-3937D01*
G01Y3937D02*
Y35433D01*
G01X505897Y0D02*
X620827D01*
G01X505897Y7615D02*
Y0D01*
G01X597244Y31496D02*
X505897D01*
G01Y7615D02*
G03X498023I-3937J0D01*
G01Y31496D02*
G03X505897I3937J0D01*
G01X498032Y1933071D02*
Y1960630D01*
G01Y1933071D02*
G03X501969Y1929134I3937J0D01*
G01X631890D02*
X501969D01*
G01X498032Y1933071D02*
Y1964567D01*
G01Y1933071D02*
G03X501969Y1929134I3937J0D01*
G01X631890D02*
X501969D01*
G01X505906Y1960630D02*
Y1968504D01*
G01D02*
X648386D01*
G01X597244Y1937008D02*
X505906D01*
G01X498032Y1960630D02*
G03X505906I3937J0D01*
G01Y1937008D02*
G03X498032I-3937J0D01*
G01X505906Y1960630D02*
Y1968504D01*
G01D02*
X620827D01*
G01X597244Y1937008D02*
X505906D01*
G01X498032Y1960630D02*
G03X505906I3937J0D01*
G01Y1937008D02*
G03X498032I-3937J0D01*
G01X575349Y-152763D02*
Y-135263D01*
X572729Y-138763D01*
G01Y-152763D02*
X577969D01*
G01X588701Y-138180D02*
X590011Y-136430D01*
X591539Y-135555D01*
X593286Y-135263D01*
X595469Y-135846D01*
X596997Y-137305D01*
X597434Y-139054D01*
X597216Y-140805D01*
X596342Y-142263D01*
X591976Y-145180D01*
X590011Y-147221D01*
X588701Y-150139D01*
X588264Y-152763D01*
X597434D01*
G01X606419Y-153346D02*
X614279Y-135263D01*
G01X627849Y-152763D02*
Y-135263D01*
X625229Y-138763D01*
G01Y-152763D02*
X630469D01*
G01X645349D02*
Y-135263D01*
X642729Y-138763D01*
G01Y-152763D02*
X647969D01*
G01X658919Y-153346D02*
X666779Y-135263D01*
G01X676201Y-138180D02*
X677511Y-136430D01*
X679039Y-135555D01*
X680786Y-135263D01*
X682969Y-135846D01*
X684497Y-137305D01*
X684934Y-139054D01*
X684716Y-140805D01*
X683842Y-142263D01*
X679476Y-145180D01*
X677511Y-147221D01*
X676201Y-150139D01*
X675764Y-152763D01*
X684934D01*
G01X697849Y-135263D02*
X696102Y-135846D01*
X694792Y-137305D01*
X693919Y-139054D01*
X693264Y-141388D01*
X693046Y-144013D01*
X693264Y-146638D01*
X693919Y-148972D01*
X694792Y-150722D01*
X696102Y-152180D01*
X697849Y-152763D01*
X699595Y-152180D01*
X700906Y-150722D01*
X701779Y-148972D01*
X702434Y-146638D01*
X702652Y-144013D01*
X702434Y-141388D01*
X701779Y-139054D01*
X700906Y-137305D01*
X699595Y-135846D01*
X697849Y-135263D01*
G01X715349Y-152763D02*
Y-135263D01*
X712729Y-138763D01*
G01Y-152763D02*
X717969D01*
G01X728046Y-150139D02*
X729355Y-151597D01*
X730884Y-152471D01*
X732849Y-152763D01*
X734814Y-152180D01*
X736342Y-151013D01*
X737434Y-148972D01*
X737652Y-146638D01*
X737216Y-144305D01*
X736124Y-142846D01*
X734595Y-141680D01*
X733067Y-141388D01*
X731539Y-141680D01*
X729574Y-142846D01*
X730229Y-135263D01*
X736124D01*
G01X623046Y-107763D02*
Y-90263D01*
X627412D01*
X629159Y-91138D01*
X630469Y-92305D01*
X631561Y-94054D01*
X632434Y-96097D01*
X632652Y-99013D01*
X632434Y-101930D01*
X631561Y-103972D01*
X630469Y-105722D01*
X629159Y-106888D01*
X627412Y-107763D01*
X623046D01*
G01X649279D02*
Y-96097D01*
G01Y-98138D02*
X648406Y-96972D01*
X647095Y-96388D01*
X645567Y-96097D01*
X644039Y-96680D01*
X642729Y-97846D01*
X641855Y-99596D01*
X641419Y-101930D01*
X641855Y-104263D01*
X642729Y-106013D01*
X644039Y-107180D01*
X645567Y-107763D01*
X647095Y-107471D01*
X648406Y-106597D01*
X649279Y-105430D01*
G01X662849Y-90263D02*
Y-107763D01*
G01X659792Y-96097D02*
X665906D01*
G01X677074Y-99888D02*
X684061D01*
X683406Y-97846D01*
X682314Y-96680D01*
X680786Y-96097D01*
X679257Y-96388D01*
X677947Y-97263D01*
X677074Y-99305D01*
X676637Y-101055D01*
Y-102805D01*
X677074Y-104555D01*
X678166Y-106305D01*
X679476Y-107471D01*
X681004Y-107763D01*
X682532Y-107180D01*
X684061Y-105430D01*
G01X643701Y169256D02*
Y39370D01*
G01X635827Y31496D02*
G03X643701Y39370I0J7874D01*
G01X650689Y19685D02*
G03I-6988J0D01*
G01X631890Y39370D02*
G03X635827Y43307I0J3937D01*
G01Y31496D02*
X627953D01*
G01X597244D02*
G03Y39370I0J3937D01*
G01X627953D02*
G03Y31496I0J-3937D01*
G01X650689Y19685D02*
G03I-6988J0D01*
G01X631890Y39370D02*
G03X635827Y43307I0J3937D01*
G01Y31496D02*
X627953D01*
G01X597244D02*
G03Y39370I0J3937D01*
G01X627953D02*
G03Y31496I0J-3937D01*
G01X635827Y161417D02*
Y43307D01*
G01X643701Y169256D02*
G03X635827I-3937J0D01*
G01X643701D02*
G03X635827I-3937J0D01*
G01Y161417D02*
Y1807087D01*
G01Y161417D02*
Y1807087D01*
G01X643701Y436186D02*
Y199965D01*
G01X635827D02*
G03X643701I3937J0D01*
G01X635827D02*
G03X643701I3937J0D01*
G01Y436186D02*
G03X635827I-3937J0D01*
G01X643701D02*
G03X635827I-3937J0D01*
G01X643701Y703115D02*
Y466894D01*
G01X635827D02*
G03X643701I3937J0D01*
G01X635827D02*
G03X643701I3937J0D01*
G01Y703115D02*
G03X635827I-3937J0D01*
G01X643701D02*
G03X635827I-3937J0D01*
G01X643701Y970832D02*
Y733823D01*
G01X635827D02*
G03X643701I3937J0D01*
G01X635827D02*
G03X643701I3937J0D01*
G01Y1234611D02*
Y997603D01*
G01X635827D02*
G03X643701I3937J0D01*
G01Y970832D02*
G03X635827I-3937J0D01*
G01Y997603D02*
G03X643701I3937J0D01*
G01Y970832D02*
G03X635827I-3937J0D01*
G01X643701Y1501541D02*
Y1265320D01*
G01X635827D02*
G03X643701I3937J0D01*
G01Y1234611D02*
G03X635827I-3937J0D01*
G01Y1265320D02*
G03X643701I3937J0D01*
G01Y1234611D02*
G03X635827I-3937J0D01*
G01X643701Y1501541D02*
G03X635827I-3937J0D01*
G01X643701D02*
G03X635827I-3937J0D01*
G01X643701Y1768470D02*
Y1532249D01*
G01X635827D02*
G03X643701I3937J0D01*
G01X635827D02*
G03X643701I3937J0D01*
G01Y1768470D02*
G03X635827I-3937J0D01*
G01X643701D02*
G03X635827I-3937J0D01*
G01Y1799178D02*
G03X643701I3937J0D01*
G01X635827D02*
G03X643701I3937J0D01*
G01Y1929134D02*
Y1799178D01*
G01X635827Y1818898D02*
Y1807087D01*
G01Y1818898D02*
Y1925197D01*
G01Y1818898D02*
Y1925197D01*
G01X643701Y1929134D02*
G03X635827Y1937008I-7874J0D01*
G01Y1925197D02*
G03X631890Y1929134I-3937J0D01*
G01X627953Y1937008D02*
G03Y1929134I0J-3937D01*
G01X597244D02*
G03Y1937008I0J3937D01*
G01X635827Y1925197D02*
G03X631890Y1929134I-3937J0D01*
G01X627953Y1937008D02*
G03Y1929134I0J-3937D01*
G01X597244D02*
G03Y1937008I0J3937D01*
G01X650689Y1948819D02*
G03I-6988J0D01*
G01X627953Y1937008D02*
X635827D01*
G01X650689Y1948819D02*
G03I-6988J0D01*
G01X627953Y1937008D02*
X635827D01*
G01X650689Y1948819D02*
G03I-6988J0D01*
G01X648386Y0D02*
G03X663386Y15000I0J15000D01*
G01Y1953504D02*
Y15000D01*
G01Y1953504D02*
G03X648386Y1968504I-15000J0D01*
G54D47*
X66875Y674606D03*
X69435D03*
X71995D03*
Y681106D03*
X66875D03*
G54D29*
X21350Y1781000D03*
X34650D03*
X77953Y54502D03*
X71650Y584000D03*
X58350D03*
X45050Y593000D03*
X58350D03*
X81850Y715400D03*
X81350Y740400D03*
X60150Y1011800D03*
X73450D03*
X64450Y1032100D03*
X77750D03*
X91253Y54502D03*
X95850Y68500D03*
X109150D03*
X95150Y715400D03*
X94650Y740400D03*
G54D65*
X111882Y1461600D03*
X114441D03*
X117000D03*
X119559D03*
X122118D03*
Y1442400D03*
X119559D03*
X117000D03*
X114441D03*
X111882D03*
G54D38*
X71802Y56547D03*
X71400Y71754D03*
X75200Y741500D03*
X75700Y719100D03*
X53800Y1013100D03*
X103500Y597500D03*
X146365Y611321D03*
G54D56*
X51800Y1760300D03*
X102200Y553300D03*
X90400Y537800D03*
X99700D03*
X116500Y603500D03*
X111200Y593700D03*
X174200Y536400D03*
X164500Y536500D03*
G54D48*
X49900Y883800D03*
Y894800D03*
X63800Y986600D03*
Y975600D03*
X39000Y1022500D03*
Y1033500D03*
X96000Y931000D03*
Y942000D03*
X147000Y732000D03*
Y721000D03*
G54D66*
X126600Y1457118D03*
Y1454559D03*
Y1452000D03*
Y1449441D03*
Y1446882D03*
X107400D03*
Y1449441D03*
Y1452000D03*
Y1454559D03*
Y1457118D03*
G36*
G01X96467Y1729085D02*
G03X96447I-10J18750D01*
G01Y1737885D01*
G02X96467I10J9950D01*
G01Y1729085D01*
G37*
G36*
G01Y1804281D02*
G03X96447I-10J18750D01*
G01Y1813081D01*
G02X96467I10J9950D01*
G01Y1804281D01*
G37*
G36*
G01X178947Y1309990D02*
G03X178927I-10J18750D01*
G01Y1318790D01*
G02X178947I10J9950D01*
G01Y1309990D01*
G37*
G36*
G01X161427Y1729085D02*
G03X161407I-10J18750D01*
G01Y1737885D01*
G02X161427I10J9950D01*
G01Y1729085D01*
G37*
G36*
G01Y1804281D02*
G03X161407I-10J18750D01*
G01Y1813081D01*
G02X161427I10J9950D01*
G01Y1804281D01*
G37*
G54D39*
X71802Y52947D03*
X71400Y68154D03*
X75200Y737900D03*
X75700Y715500D03*
X53800Y1009500D03*
X103500Y593900D03*
X146365Y607721D03*
G54D49*
X86699Y949600D03*
X63901D03*
G54D67*
X117000Y1452000D03*
G54D58*
X136235Y618504D03*
Y620469D03*
Y622439D03*
Y624409D03*
Y626374D03*
Y628344D03*
Y630314D03*
Y632284D03*
Y634249D03*
Y636219D03*
Y638189D03*
Y640154D03*
X102835D03*
Y638189D03*
Y636219D03*
Y634249D03*
Y632284D03*
Y630314D03*
Y628344D03*
Y626374D03*
Y624409D03*
Y622439D03*
Y620469D03*
Y618504D03*
G54D59*
X89435Y642629D03*
Y635029D03*
X89500Y1461700D03*
Y1469300D03*
X172100Y549100D03*
Y541500D03*
X152265Y601371D03*
X170100Y607600D03*
Y615200D03*
X152265Y608971D03*
X167000Y1457700D03*
Y1465300D03*
G54D68*
X171370Y634819D03*
X159800D03*
X171370Y645839D03*
X159800D03*
G54D69*
X180465Y631371D03*
Y634971D03*
M02*
